FILE_TYPE = MACRO_DRAWING;
SET COLOR_WIRE YELLOW;
SET COLOR_PROP MONO;
SET COLOR_DOT WHITE;
SET COLOR_ARC YELLOW;
SET COLOR_BODY GREEN;
SET COLOR_NOTE MONO;
SET PROP_DISPLAY VALUE;
SET PAGE_NUMBER P230;
FORCEADD GND..1
(3750 3050);
FORCEPROP 3 LASTPIN (3750 3100) SIG_NAME GND\g
J 0
(3760 3110);
DISPLAY 0.659574 (3760 3110);
PAINT MONO (3760 3110);
DISPLAY INVISIBLE (3760 3110);
FORCEPROP 1 LAST SIZE 1B
J 0
(3825 3000);
DISPLAY 0.893617 (3825 3000);
PAINT GREEN (3825 3000);
DISPLAY INVISIBLE (3825 3000);
FORCEPROP 1 LAST BODY_TYPE PLUMBING
J 0
(3705 3007);
DISPLAY 0.340426 (3705 3007);
PAINT GREEN (3705 3007);
DISPLAY INVISIBLE (3705 3007);
FORCEPROP 1 LAST VOLTAGE 0.0V
J 0
(3705 3007);
DISPLAY 0.340426 (3705 3007);
PAINT SKYBLUE (3705 3007);
DISPLAY INVISIBLE (3705 3007);
FORCEPROP 2 LAST CDS_LIB mstr_symbols
J 0
(3750 3050);
PAINT ORANGE (3750 3050);
DISPLAY INVISIBLE (3750 3050);
FORCEPROP 1 LAST PATH I10
J 0
(3825 3050);
DISPLAY 0.872340 (3825 3050);
PAINT AQUA (3825 3050);
DISPLAY INVISIBLE (3825 3050);
FORCEPROP 2 LAST ROOM VTT_KLM_PWR_VR
J 0
(3200 3125);
PAINT ORANGE (3200 3125);
DISPLAY INVISIBLE (3200 3125);
FORCEPROP 2 LAST BOM_COST MEM_KLM_VTT_DEF
J 0
(3425 3125);
PAINT MONO (3425 3125);
DISPLAY INVISIBLE (3425 3125);
FORCEPROP 1 LAST HDL_POWER GND
J 0
(3750 3200);
DISPLAY 0.893617 (3750 3200);
PAINT GREEN (3750 3200);
DISPLAY INVISIBLE (3750 3200);
FORCEADD GND..1
(3875 1400);
FORCEPROP 3 LASTPIN (3875 1450) SIG_NAME GND\g
J 0
(3885 1460);
DISPLAY 0.659574 (3885 1460);
PAINT MONO (3885 1460);
DISPLAY INVISIBLE (3885 1460);
FORCEPROP 1 LAST BODY_TYPE PLUMBING
J 0
(3830 1357);
DISPLAY 0.340426 (3830 1357);
PAINT GREEN (3830 1357);
DISPLAY INVISIBLE (3830 1357);
FORCEPROP 1 LAST VOLTAGE 0.0V
J 0
(3830 1357);
DISPLAY 0.340426 (3830 1357);
PAINT SKYBLUE (3830 1357);
DISPLAY INVISIBLE (3830 1357);
FORCEPROP 1 LAST PATH I15
J 0
(3950 1400);
DISPLAY 0.872340 (3950 1400);
PAINT AQUA (3950 1400);
DISPLAY INVISIBLE (3950 1400);
FORCEPROP 2 LAST CDS_LIB mstr_symbols
J 0
(3875 1400);
DISPLAY 0.744681 (3875 1400);
PAINT MONO (3875 1400);
DISPLAY INVISIBLE (3875 1400);
FORCEPROP 1 LAST SIZE 1B
J 0
(3950 1350);
DISPLAY 0.893617 (3950 1350);
PAINT GREEN (3950 1350);
DISPLAY INVISIBLE (3950 1350);
FORCEPROP 1 LAST HDL_POWER GND
J 0
(3875 1550);
DISPLAY 0.893617 (3875 1550);
PAINT GREEN (3875 1550);
DISPLAY INVISIBLE (3875 1550);
FORCEADD CAP..1
R 2
(3875 1650);
FORCEPROP 1 LAST PART_NUMBER A36096-046
J 2
(3825 1500);
DISPLAY 0.617021 (3825 1500);
PAINT BLUE (3825 1500);
FORCEPROP 1 LAST PACK_TYPE 0402LF
J 2
(3825 1450);
DISPLAY 0.617021 (3825 1450);
PAINT SKYBLUE (3825 1450);
FORCEPROP 1 LASTPIN (3875 1550) $PN 2
J 2
(3865 1530);
DISPLAY 0.617021 (3865 1530);
PAINT WHITE (3865 1530);
FORCEPROP 1 LAST LOCATION C4A3
J 2
(3825 1750);
DISPLAY 0.617021 (3825 1750);
PAINT AQUA (3825 1750);
FORCEPROP 1 LAST VALUE 1000PF
J 2
(3825 1700);
DISPLAY 0.617021 (3825 1700);
PAINT SKYBLUE (3825 1700);
FORCEPROP 1 LAST TOLERANCE 10%
J 2
(3825 1600);
DISPLAY 0.617021 (3825 1600);
PAINT SKYBLUE (3825 1600);
FORCEPROP 1 LAST VOLTAGE 50V
J 2
(3825 1650);
DISPLAY 0.617021 (3825 1650);
PAINT SKYBLUE (3825 1650);
FORCEPROP 1 LAST MATERIAL X7R
J 2
(3825 1550);
DISPLAY 0.617021 (3825 1550);
PAINT SKYBLUE (3825 1550);
FORCEPROP 1 LASTPIN (3875 1750) $PN 1
J 2
(3865 1730);
DISPLAY 0.617021 (3865 1730);
PAINT WHITE (3865 1730);
FORCEPROP 2 LAST SEC 1
J 2
(3825 1850);
DISPLAY 0.680851 (3825 1850);
PAINT MONO (3825 1850);
DISPLAY INVISIBLE (3825 1850);
FORCEPROP 2 LAST CDS_LOCATION C4A3
J 2
(3825 1750);
DISPLAY 0.617021 (3825 1750);
PAINT AQUA (3825 1750);
DISPLAY INVISIBLE (3825 1750);
FORCEPROP 1 LAST PATH I16
J 2
(3825 1800);
DISPLAY 0.978723 (3825 1800);
PAINT WHITE (3825 1800);
DISPLAY INVISIBLE (3825 1800);
FORCEPROP 2 LAST SEC_TYPE 0402LF
J 2
(3825 1850);
DISPLAY 1.021277 (3825 1850);
PAINT ORANGE (3825 1850);
DISPLAY INVISIBLE (3825 1850);
FORCEPROP 2 LAST BOM_COST MEM_VRD_VTT_KLM
J 2
(3825 1850);
DISPLAY 1.021277 (3825 1850);
PAINT ORANGE (3825 1850);
DISPLAY INVISIBLE (3825 1850);
FORCEPROP 2 LAST ROOM VTT_KLM_PWR_VR
J 2
(3825 1800);
DISPLAY 1.021277 (3825 1800);
PAINT ORANGE (3825 1800);
DISPLAY INVISIBLE (3825 1800);
FORCEPROP 2 LAST CDS_LIB mstr_discrete
J 2
(3875 1650);
DISPLAY 0.744681 (3875 1650);
PAINT MONO (3875 1650);
DISPLAY INVISIBLE (3875 1650);
FORCEADD RES..2
R 2
(3500 2025);
FORCEPROP 1 LAST WATTAGE 1/16W
J 2
(3460 2000);
DISPLAY 0.617021 (3460 2000);
PAINT SKYBLUE (3460 2000);
FORCEPROP 1 LAST PART_NUMBER G21796-016
J 2
(3460 1900);
DISPLAY 0.617021 (3460 1900);
PAINT BLUE (3460 1900);
FORCEPROP 1 LAST MATERIAL CHIP
J 2
(3460 1950);
DISPLAY 0.617021 (3460 1950);
PAINT SKYBLUE (3460 1950);
FORCEPROP 1 LAST PACK_TYPE 0402
J 2
(3460 1850);
DISPLAY 0.617021 (3460 1850);
PAINT SKYBLUE (3460 1850);
FORCEPROP 1 LASTPIN (3500 1925) $PN 2
J 2
(3495 1935);
DISPLAY 0.617021 (3495 1935);
PAINT WHITE (3495 1935);
FORCEPROP 1 LAST VALUE 10.0K
J 2
(3455 2100);
DISPLAY 0.617021 (3455 2100);
PAINT SKYBLUE (3455 2100);
FORCEPROP 1 LAST LOCATION R4A5
J 2
(3455 2150);
DISPLAY 0.617021 (3455 2150);
PAINT AQUA (3455 2150);
FORCEPROP 1 LAST TOLERANCE 1%
J 2
(3455 2050);
DISPLAY 0.617021 (3455 2050);
PAINT SKYBLUE (3455 2050);
FORCEPROP 1 LASTPIN (3500 2125) $PN 1
J 2
(3495 2087);
DISPLAY 0.617021 (3495 2087);
PAINT WHITE (3495 2087);
FORCEPROP 2 LAST CDS_LIB mstr_discrete
J 2
(3500 2025);
PAINT ORANGE (3500 2025);
DISPLAY INVISIBLE (3500 2025);
FORCEPROP 2 LAST ROOM VTT_KLM_PWR_VR
J 2
(3450 2200);
DISPLAY 1.021277 (3450 2200);
PAINT ORANGE (3450 2200);
DISPLAY INVISIBLE (3450 2200);
FORCEPROP 1 LAST PATH I17
J 2
(3450 2200);
DISPLAY 0.978723 (3450 2200);
PAINT WHITE (3450 2200);
DISPLAY INVISIBLE (3450 2200);
FORCEPROP 2 LAST CDS_LOCATION R4A5
J 2
(3455 2150);
DISPLAY 0.617021 (3455 2150);
PAINT AQUA (3455 2150);
DISPLAY INVISIBLE (3455 2150);
FORCEPROP 2 LAST SEC 1
J 2
(3450 2246);
DISPLAY 0.680851 (3450 2246);
PAINT MONO (3450 2246);
DISPLAY INVISIBLE (3450 2246);
FORCEPROP 2 LAST BOM_COST MEM_VRD_VTT_KLM
J 2
(3450 2250);
DISPLAY 1.021277 (3450 2250);
PAINT ORANGE (3450 2250);
DISPLAY INVISIBLE (3450 2250);
FORCEPROP 2 LAST SEC_TYPE 0402
J 2
(3450 2246);
DISPLAY 1.021277 (3450 2246);
PAINT ORANGE (3450 2246);
DISPLAY INVISIBLE (3450 2246);
FORCEADD CAP..1
(4000 1050);
FORCEPROP 1 LASTPIN (4000 950) $PN 2
J 0
(4010 930);
DISPLAY 0.617021 (4010 930);
PAINT WHITE (4010 930);
FORCEPROP 1 LAST PART_NUMBER C95333-002
R 1
J 0
(3950 900);
DISPLAY 0.617021 (3950 900);
PAINT BLUE (3950 900);
FORCEPROP 1 LASTPIN (4000 1150) $PN 1
J 0
(4010 1130);
DISPLAY 0.617021 (4010 1130);
PAINT WHITE (4010 1130);
FORCEPROP 1 LAST MATERIAL X6S
J 0
(4050 950);
DISPLAY 0.617021 (4050 950);
PAINT SKYBLUE (4050 950);
FORCEPROP 1 LAST VOLTAGE 4V
J 0
(4050 1050);
DISPLAY 0.617021 (4050 1050);
PAINT SKYBLUE (4050 1050);
FORCEPROP 1 LAST PACK_TYPE 0805LF
J 0
(4050 900);
DISPLAY 0.617021 (4050 900);
PAINT SKYBLUE (4050 900);
FORCEPROP 1 LAST TOLERANCE 20%
J 0
(4050 1000);
DISPLAY 0.617021 (4050 1000);
PAINT SKYBLUE (4050 1000);
FORCEPROP 1 LAST VALUE 22UF
J 0
(4050 1100);
DISPLAY 0.617021 (4050 1100);
PAINT SKYBLUE (4050 1100);
FORCEPROP 1 LAST LOCATION C4A13
J 0
(4050 1150);
DISPLAY 0.617021 (4050 1150);
PAINT AQUA (4050 1150);
FORCEPROP 2 LAST CDS_LIB mstr_discrete
J 0
(4000 1050);
PAINT ORANGE (4000 1050);
DISPLAY INVISIBLE (4000 1050);
FORCEPROP 2 LAST CDS_LOCATION C4A13
J 0
(4050 1150);
DISPLAY 0.617021 (4050 1150);
PAINT AQUA (4050 1150);
DISPLAY INVISIBLE (4050 1150);
FORCEPROP 1 LAST PATH I18
J 0
(4050 1200);
DISPLAY 0.978723 (4050 1200);
PAINT WHITE (4050 1200);
DISPLAY INVISIBLE (4050 1200);
FORCEPROP 2 LAST ROOM VTT_KLM_PWR_VR
J 0
(4070 1205);
DISPLAY 1.021277 (4070 1205);
PAINT ORANGE (4070 1205);
DISPLAY INVISIBLE (4070 1205);
FORCEPROP 2 LAST SEC_TYPE 0805LF
J 0
(4051 1270);
DISPLAY 1.021277 (4051 1270);
PAINT ORANGE (4051 1270);
DISPLAY INVISIBLE (4051 1270);
FORCEPROP 2 LAST BOM_COST MEM_VRD_VTT_KLM
J 0
(4070 1255);
DISPLAY 1.021277 (4070 1255);
PAINT ORANGE (4070 1255);
DISPLAY INVISIBLE (4070 1255);
FORCEPROP 2 LAST SEC 1
J 0
(4051 1270);
DISPLAY 0.680851 (4051 1270);
PAINT MONO (4051 1270);
DISPLAY INVISIBLE (4051 1270);
FORCEADD GND..1
(4000 675);
FORCEPROP 3 LASTPIN (4000 725) SIG_NAME GND\g
J 0
(4010 735);
DISPLAY 0.659574 (4010 735);
PAINT MONO (4010 735);
DISPLAY INVISIBLE (4010 735);
FORCEPROP 1 LAST SIZE 1B
J 0
(4075 625);
DISPLAY 0.893617 (4075 625);
PAINT GREEN (4075 625);
DISPLAY INVISIBLE (4075 625);
FORCEPROP 2 LAST CDS_LIB mstr_symbols
J 0
(4000 675);
PAINT ORANGE (4000 675);
DISPLAY INVISIBLE (4000 675);
FORCEPROP 1 LAST BODY_TYPE PLUMBING
J 0
(3955 632);
DISPLAY 0.340426 (3955 632);
PAINT GREEN (3955 632);
DISPLAY INVISIBLE (3955 632);
FORCEPROP 1 LAST PATH I19
J 0
(4075 675);
DISPLAY 0.872340 (4075 675);
PAINT AQUA (4075 675);
DISPLAY INVISIBLE (4075 675);
FORCEPROP 1 LAST VOLTAGE 0.0V
J 0
(3955 632);
DISPLAY 0.340426 (3955 632);
PAINT SKYBLUE (3955 632);
DISPLAY INVISIBLE (3955 632);
FORCEPROP 1 LAST HDL_POWER GND
J 0
(4000 825);
DISPLAY 0.893617 (4000 825);
PAINT GREEN (4000 825);
DISPLAY INVISIBLE (4000 825);
FORCEADD CAP..1
(2350 875);
FORCEPROP 1 LASTPIN (2350 775) $PN 2
J 0
(2360 755);
DISPLAY 0.617021 (2360 755);
PAINT WHITE (2360 755);
FORCEPROP 1 LASTPIN (2350 975) $PN 1
J 0
(2360 955);
DISPLAY 0.617021 (2360 955);
PAINT WHITE (2360 955);
FORCEPROP 1 LAST PACK_TYPE 0402
J 0
(2400 775);
DISPLAY 0.617021 (2400 775);
PAINT SKYBLUE (2400 775);
FORCEPROP 1 LAST TOLERANCE 10%
J 0
(2400 875);
DISPLAY 0.617021 (2400 875);
PAINT SKYBLUE (2400 875);
FORCEPROP 1 LAST VALUE 1.0UF
J 0
(2400 925);
DISPLAY 0.617021 (2400 925);
PAINT SKYBLUE (2400 925);
FORCEPROP 1 LAST LOCATION C4A14
J 0
(2400 975);
DISPLAY 0.617021 (2400 975);
PAINT AQUA (2400 975);
FORCEPROP 1 LAST MATERIAL X6S
J 0
(2525 875);
DISPLAY 0.617021 (2525 875);
PAINT SKYBLUE (2525 875);
FORCEPROP 1 LAST VOLTAGE 16V
J 0
(2550 925);
DISPLAY 0.617021 (2550 925);
PAINT SKYBLUE (2550 925);
FORCEPROP 1 LAST PART_NUMBER D97712-011
J 0
(2400 825);
DISPLAY 0.617021 (2400 825);
PAINT BLUE (2400 825);
FORCEPROP 2 LAST CDS_LIB mstr_discrete
J 0
(2350 875);
PAINT ORANGE (2350 875);
DISPLAY INVISIBLE (2350 875);
FORCEPROP 2 LAST CDS_LOCATION C4A14
J 0
(2400 975);
DISPLAY 0.617021 (2400 975);
PAINT AQUA (2400 975);
DISPLAY INVISIBLE (2400 975);
FORCEPROP 2 LAST SEC_TYPE 0402
J 0
(2406 1090);
DISPLAY 1.021277 (2406 1090);
PAINT ORANGE (2406 1090);
DISPLAY INVISIBLE (2406 1090);
FORCEPROP 2 LAST BOM_COST MEM_VRD_VTT_KLM
J 0
(2400 1075);
DISPLAY 1.021277 (2400 1075);
PAINT ORANGE (2400 1075);
DISPLAY INVISIBLE (2400 1075);
FORCEPROP 2 LAST SEC 1
J 0
(2406 1090);
DISPLAY 0.680851 (2406 1090);
PAINT MONO (2406 1090);
DISPLAY INVISIBLE (2406 1090);
FORCEPROP 1 LAST PATH I21
J 0
(2400 1025);
DISPLAY 0.978723 (2400 1025);
PAINT WHITE (2400 1025);
DISPLAY INVISIBLE (2400 1025);
FORCEPROP 2 LAST ROOM VTT_KLM_PWR_VR
J 0
(2400 1025);
DISPLAY 1.021277 (2400 1025);
PAINT ORANGE (2400 1025);
DISPLAY INVISIBLE (2400 1025);
FORCEADD GND..1
(2350 600);
FORCEPROP 3 LASTPIN (2350 650) SIG_NAME GND\g
J 0
(2360 660);
DISPLAY 0.659574 (2360 660);
PAINT MONO (2360 660);
DISPLAY INVISIBLE (2360 660);
FORCEPROP 2 LAST CDS_LIB mstr_symbols
J 0
(2350 600);
PAINT ORANGE (2350 600);
DISPLAY INVISIBLE (2350 600);
FORCEPROP 1 LAST SIZE 1B
J 0
(2425 550);
DISPLAY 0.872340 (2425 550);
PAINT AQUA (2425 550);
DISPLAY INVISIBLE (2425 550);
FORCEPROP 1 LAST PATH I22
J 0
(2425 600);
DISPLAY 0.872340 (2425 600);
PAINT AQUA (2425 600);
DISPLAY INVISIBLE (2425 600);
FORCEPROP 1 LAST BODY_TYPE PLUMBING
J 0
(2305 557);
DISPLAY 0.340426 (2305 557);
PAINT GREEN (2305 557);
DISPLAY INVISIBLE (2305 557);
FORCEPROP 1 LAST VOLTAGE 0.0V
J 0
(2305 557);
DISPLAY 0.340426 (2305 557);
PAINT SKYBLUE (2305 557);
DISPLAY INVISIBLE (2305 557);
FORCEPROP 1 LAST HDL_POWER GND
J 0
(2350 750);
DISPLAY 0.872340 (2350 750);
PAINT GREEN (2350 750);
DISPLAY INVISIBLE (2350 750);
FORCEADD GND..1
(2025 600);
FORCEPROP 3 LASTPIN (2025 650) SIG_NAME GND\g
J 0
(2035 660);
DISPLAY 0.659574 (2035 660);
PAINT MONO (2035 660);
DISPLAY INVISIBLE (2035 660);
FORCEPROP 2 LAST CDS_LIB mstr_symbols
J 0
(2025 600);
PAINT ORANGE (2025 600);
DISPLAY INVISIBLE (2025 600);
FORCEPROP 1 LAST BODY_TYPE PLUMBING
J 0
(1980 557);
DISPLAY 0.340426 (1980 557);
PAINT GREEN (1980 557);
DISPLAY INVISIBLE (1980 557);
FORCEPROP 1 LAST VOLTAGE 0.0V
J 0
(1980 557);
DISPLAY 0.340426 (1980 557);
PAINT SKYBLUE (1980 557);
DISPLAY INVISIBLE (1980 557);
FORCEPROP 1 LAST HDL_POWER GND
J 0
(2025 750);
DISPLAY 0.872340 (2025 750);
PAINT GREEN (2025 750);
DISPLAY INVISIBLE (2025 750);
FORCEPROP 1 LAST PATH I23
J 0
(2100 600);
DISPLAY 0.872340 (2100 600);
PAINT AQUA (2100 600);
DISPLAY INVISIBLE (2100 600);
FORCEPROP 1 LAST SIZE 1B
J 0
(2100 550);
DISPLAY 0.872340 (2100 550);
PAINT AQUA (2100 550);
DISPLAY INVISIBLE (2100 550);
FORCEADD GND..1
(475 2125);
FORCEPROP 3 LASTPIN (475 2175) SIG_NAME GND\g
J 0
(485 2185);
DISPLAY 0.659574 (485 2185);
PAINT MONO (485 2185);
DISPLAY INVISIBLE (485 2185);
FORCEPROP 2 LAST BOM_COST MEM_VRD_VTT_KLM
J 0
(-30 2255);
DISPLAY 1.021277 (-30 2255);
PAINT ORANGE (-30 2255);
DISPLAY INVISIBLE (-30 2255);
FORCEPROP 2 LAST ROOM VTT_KLM_PWR_VR
J 0
(-30 2205);
DISPLAY 1.021277 (-30 2205);
PAINT ORANGE (-30 2205);
DISPLAY INVISIBLE (-30 2205);
FORCEPROP 2 LAST CDS_LIB mstr_symbols
J 0
(475 2125);
PAINT MONO (475 2125);
DISPLAY INVISIBLE (475 2125);
FORCEPROP 1 LAST BODY_TYPE PLUMBING
J 0
(430 2082);
DISPLAY 0.340426 (430 2082);
PAINT GREEN (430 2082);
DISPLAY INVISIBLE (430 2082);
FORCEPROP 1 LAST VOLTAGE 0.0V
J 0
(430 2082);
DISPLAY 0.340426 (430 2082);
PAINT SKYBLUE (430 2082);
DISPLAY INVISIBLE (430 2082);
FORCEPROP 1 LAST HDL_POWER GND
J 0
(475 2275);
DISPLAY 0.893617 (475 2275);
PAINT GREEN (475 2275);
DISPLAY INVISIBLE (475 2275);
FORCEPROP 1 LAST PATH I24
J 0
(550 2125);
DISPLAY 0.872340 (550 2125);
PAINT AQUA (550 2125);
DISPLAY INVISIBLE (550 2125);
FORCEPROP 1 LAST SIZE 1B
J 0
(550 2075);
DISPLAY 0.893617 (550 2075);
PAINT GREEN (550 2075);
DISPLAY INVISIBLE (550 2075);
FORCEADD CAP..1
(475 2400);
FORCEPROP 1 LASTPIN (475 2300) $PN 2
J 0
(485 2280);
DISPLAY 0.617021 (485 2280);
PAINT WHITE (485 2280);
FORCEPROP 1 LASTPIN (475 2500) $PN 1
J 0
(485 2480);
DISPLAY 0.617021 (485 2480);
PAINT WHITE (485 2480);
FORCEPROP 1 LAST LOCATION C4A15
J 0
(525 2500);
DISPLAY 0.617021 (525 2500);
PAINT AQUA (525 2500);
FORCEPROP 1 LAST PART_NUMBER E15431-001
J 0
(525 2250);
DISPLAY 0.617021 (525 2250);
PAINT BLUE (525 2250);
FORCEPROP 1 LAST VALUE 10UF
J 0
(525 2450);
DISPLAY 0.617021 (525 2450);
PAINT SKYBLUE (525 2450);
FORCEPROP 1 LAST TOLERANCE 20%
J 0
(525 2350);
DISPLAY 0.617021 (525 2350);
PAINT SKYBLUE (525 2350);
FORCEPROP 1 LAST PACK_TYPE 0603LF
J 0
(525 2200);
DISPLAY 0.617021 (525 2200);
PAINT SKYBLUE (525 2200);
FORCEPROP 1 LAST VOLTAGE 4V
J 0
(525 2400);
DISPLAY 0.617021 (525 2400);
PAINT SKYBLUE (525 2400);
FORCEPROP 1 LAST MATERIAL X6S
J 0
(525 2300);
DISPLAY 0.617021 (525 2300);
PAINT SKYBLUE (525 2300);
FORCEPROP 2 LAST CDS_LIB mstr_discrete
J 0
(475 2400);
PAINT ORANGE (475 2400);
DISPLAY INVISIBLE (475 2400);
FORCEPROP 2 LAST CDS_LOCATION C4A15
J 0
(525 2500);
DISPLAY 0.617021 (525 2500);
PAINT AQUA (525 2500);
DISPLAY INVISIBLE (525 2500);
FORCEPROP 2 LAST ROOM VTT_KLM_PWR_VR
J 0
(525 2550);
DISPLAY 1.021277 (525 2550);
PAINT ORANGE (525 2550);
DISPLAY INVISIBLE (525 2550);
FORCEPROP 1 LAST PATH I25
J 0
(525 2550);
DISPLAY 0.978723 (525 2550);
PAINT WHITE (525 2550);
DISPLAY INVISIBLE (525 2550);
FORCEPROP 2 LAST SEC 1
J 0
(531 2615);
DISPLAY 0.680851 (531 2615);
PAINT MONO (531 2615);
DISPLAY INVISIBLE (531 2615);
FORCEPROP 2 LAST SEC_TYPE 0603LF
J 0
(531 2615);
DISPLAY 1.021277 (531 2615);
PAINT ORANGE (531 2615);
DISPLAY INVISIBLE (531 2615);
FORCEPROP 2 LAST BOM_COST MEM_VRD_VTT_KLM
J 0
(525 2600);
DISPLAY 1.021277 (525 2600);
PAINT ORANGE (525 2600);
DISPLAY INVISIBLE (525 2600);
FORCEADD CAP..1
(50 2375);
FORCEPROP 1 LASTPIN (50 2275) $PN 2
J 0
(60 2255);
DISPLAY 0.617021 (60 2255);
PAINT WHITE (60 2255);
FORCEPROP 1 LAST MATERIAL X6S
J 0
(100 2275);
DISPLAY 0.617021 (100 2275);
PAINT SKYBLUE (100 2275);
FORCEPROP 1 LASTPIN (50 2475) $PN 1
J 0
(60 2455);
DISPLAY 0.617021 (60 2455);
PAINT WHITE (60 2455);
FORCEPROP 1 LAST LOCATION C6L5
J 0
(100 2475);
DISPLAY 0.617021 (100 2475);
PAINT AQUA (100 2475);
FORCEPROP 1 LAST VALUE 10UF
J 0
(100 2425);
DISPLAY 0.617021 (100 2425);
PAINT SKYBLUE (100 2425);
FORCEPROP 1 LAST TOLERANCE 20%
J 0
(100 2325);
DISPLAY 0.617021 (100 2325);
PAINT SKYBLUE (100 2325);
FORCEPROP 1 LAST VOLTAGE 4V
J 0
(100 2375);
DISPLAY 0.617021 (100 2375);
PAINT SKYBLUE (100 2375);
FORCEPROP 1 LAST PACK_TYPE 0603LF
J 0
(100 2175);
DISPLAY 0.617021 (100 2175);
PAINT SKYBLUE (100 2175);
FORCEPROP 1 LAST PART_NUMBER E15431-001
J 0
(100 2225);
DISPLAY 0.617021 (100 2225);
PAINT BLUE (100 2225);
FORCEPROP 2 LAST CDS_LOCATION C6L5
J 0
(100 2475);
DISPLAY 0.617021 (100 2475);
PAINT AQUA (100 2475);
DISPLAY INVISIBLE (100 2475);
FORCEPROP 2 LAST CDS_LIB mstr_discrete
J 0
(50 2375);
PAINT ORANGE (50 2375);
DISPLAY INVISIBLE (50 2375);
FORCEPROP 1 LAST PATH I26
J 0
(100 2525);
DISPLAY 0.978723 (100 2525);
PAINT WHITE (100 2525);
DISPLAY INVISIBLE (100 2525);
FORCEPROP 2 LAST ROOM VTT_KLM_PWR_VR
J 0
(100 2525);
DISPLAY 1.021277 (100 2525);
PAINT ORANGE (100 2525);
DISPLAY INVISIBLE (100 2525);
FORCEPROP 2 LAST BOM_COST MEM_VRD_VTT_KLM
J 0
(100 2575);
DISPLAY 1.021277 (100 2575);
PAINT ORANGE (100 2575);
DISPLAY INVISIBLE (100 2575);
FORCEPROP 2 LAST SEC_TYPE 0603LF
J 0
(106 2590);
DISPLAY 1.021277 (106 2590);
PAINT ORANGE (106 2590);
DISPLAY INVISIBLE (106 2590);
FORCEPROP 2 LAST SEC 1
J 0
(106 2590);
DISPLAY 0.680851 (106 2590);
PAINT MONO (106 2590);
DISPLAY INVISIBLE (106 2590);
FORCEADD GND..1
(50 2125);
FORCEPROP 3 LASTPIN (50 2175) SIG_NAME GND\g
J 0
(60 2185);
DISPLAY 0.659574 (60 2185);
PAINT MONO (60 2185);
DISPLAY INVISIBLE (60 2185);
FORCEPROP 2 LAST BOM_COST MEM_VRD_VTT_KLM
J 0
(-455 2255);
DISPLAY 1.021277 (-455 2255);
PAINT ORANGE (-455 2255);
DISPLAY INVISIBLE (-455 2255);
FORCEPROP 2 LAST ROOM VTT_KLM_PWR_VR
J 0
(-455 2205);
DISPLAY 1.021277 (-455 2205);
PAINT ORANGE (-455 2205);
DISPLAY INVISIBLE (-455 2205);
FORCEPROP 1 LAST SIZE 1B
J 0
(125 2075);
DISPLAY 0.893617 (125 2075);
PAINT GREEN (125 2075);
DISPLAY INVISIBLE (125 2075);
FORCEPROP 2 LAST CDS_LIB mstr_symbols
J 0
(50 2125);
DISPLAY 0.744681 (50 2125);
PAINT MONO (50 2125);
DISPLAY INVISIBLE (50 2125);
FORCEPROP 1 LAST BODY_TYPE PLUMBING
J 0
(5 2082);
DISPLAY 0.340426 (5 2082);
PAINT GREEN (5 2082);
DISPLAY INVISIBLE (5 2082);
FORCEPROP 1 LAST PATH I27
J 0
(125 2125);
DISPLAY 0.872340 (125 2125);
PAINT AQUA (125 2125);
DISPLAY INVISIBLE (125 2125);
FORCEPROP 1 LAST VOLTAGE 0.0V
J 0
(5 2082);
DISPLAY 0.340426 (5 2082);
PAINT SKYBLUE (5 2082);
DISPLAY INVISIBLE (5 2082);
FORCEPROP 1 LAST HDL_POWER GND
J 0
(50 2275);
DISPLAY 0.893617 (50 2275);
PAINT GREEN (50 2275);
DISPLAY INVISIBLE (50 2275);
FORCEADD CAP..1
(475 1525);
FORCEPROP 1 LASTPIN (475 1425) $PN 2
J 0
(485 1405);
DISPLAY 0.617021 (485 1405);
PAINT WHITE (485 1405);
FORCEPROP 1 LASTPIN (475 1625) $PN 1
J 0
(485 1605);
DISPLAY 0.617021 (485 1605);
PAINT WHITE (485 1605);
FORCEPROP 1 LAST PART_NUMBER D97712-011
J 0
(525 1475);
DISPLAY 0.617021 (525 1475);
PAINT BLUE (525 1475);
FORCEPROP 1 LAST PACK_TYPE 0402
J 0
(525 1425);
DISPLAY 0.617021 (525 1425);
PAINT SKYBLUE (525 1425);
FORCEPROP 1 LAST TOLERANCE 10%
J 0
(525 1525);
DISPLAY 0.617021 (525 1525);
PAINT SKYBLUE (525 1525);
FORCEPROP 1 LAST MATERIAL X6S
J 0
(650 1525);
DISPLAY 0.617021 (650 1525);
PAINT SKYBLUE (650 1525);
FORCEPROP 1 LAST LOCATION C4A8
J 0
(525 1625);
DISPLAY 0.617021 (525 1625);
PAINT AQUA (525 1625);
FORCEPROP 1 LAST VALUE 1.0UF
J 0
(525 1575);
DISPLAY 0.617021 (525 1575);
PAINT SKYBLUE (525 1575);
FORCEPROP 1 LAST VOLTAGE 16V
J 0
(675 1575);
DISPLAY 0.617021 (675 1575);
PAINT SKYBLUE (675 1575);
FORCEPROP 2 LAST CDS_LIB mstr_discrete
J 0
(475 1525);
PAINT ORANGE (475 1525);
DISPLAY INVISIBLE (475 1525);
FORCEPROP 2 LAST ROOM VTT_KLM_PWR_VR
J 0
(525 1675);
DISPLAY 1.021277 (525 1675);
PAINT ORANGE (525 1675);
DISPLAY INVISIBLE (525 1675);
FORCEPROP 1 LAST PATH I28
J 0
(525 1675);
DISPLAY 0.978723 (525 1675);
PAINT WHITE (525 1675);
DISPLAY INVISIBLE (525 1675);
FORCEPROP 2 LAST CDS_LOCATION C4A8
J 0
(525 1625);
DISPLAY 0.617021 (525 1625);
PAINT AQUA (525 1625);
DISPLAY INVISIBLE (525 1625);
FORCEPROP 2 LAST SEC 1
J 0
(525 1721);
DISPLAY 0.680851 (525 1721);
PAINT MONO (525 1721);
DISPLAY INVISIBLE (525 1721);
FORCEPROP 2 LAST BOM_COST MEM_VRD_VTT_KLM
J 0
(525 1725);
DISPLAY 1.021277 (525 1725);
PAINT ORANGE (525 1725);
DISPLAY INVISIBLE (525 1725);
FORCEPROP 2 LAST SEC_TYPE 0402
J 0
(525 1721);
DISPLAY 1.021277 (525 1721);
PAINT ORANGE (525 1721);
DISPLAY INVISIBLE (525 1721);
FORCEADD GND..1
(475 1275);
FORCEPROP 3 LASTPIN (475 1325) SIG_NAME GND\g
J 0
(485 1335);
DISPLAY 0.659574 (485 1335);
PAINT MONO (485 1335);
DISPLAY INVISIBLE (485 1335);
FORCEPROP 1 LAST VOLTAGE 0.0V
J 0
(430 1232);
DISPLAY 0.340426 (430 1232);
PAINT SKYBLUE (430 1232);
DISPLAY INVISIBLE (430 1232);
FORCEPROP 1 LAST BODY_TYPE PLUMBING
J 0
(430 1232);
DISPLAY 0.340426 (430 1232);
PAINT GREEN (430 1232);
DISPLAY INVISIBLE (430 1232);
FORCEPROP 2 LAST CDS_LIB mstr_symbols
J 0
(475 1275);
DISPLAY 0.744681 (475 1275);
PAINT MONO (475 1275);
DISPLAY INVISIBLE (475 1275);
FORCEPROP 1 LAST HDL_POWER GND
J 0
(475 1425);
DISPLAY 0.893617 (475 1425);
PAINT GREEN (475 1425);
DISPLAY INVISIBLE (475 1425);
FORCEPROP 1 LAST PATH I29
J 0
(550 1275);
DISPLAY 0.872340 (550 1275);
PAINT AQUA (550 1275);
DISPLAY INVISIBLE (550 1275);
FORCEPROP 1 LAST SIZE 1B
J 0
(550 1225);
DISPLAY 0.893617 (550 1225);
PAINT GREEN (550 1225);
DISPLAY INVISIBLE (550 1225);
FORCEADD RES..1
(150 1775);
FORCEPROP 1 LAST WATTAGE 1/16W
J 2
(125 1625);
DISPLAY 0.617021 (125 1625);
PAINT SKYBLUE (125 1625);
FORCEPROP 1 LAST VALUE 0.0
J 2
(125 1675);
DISPLAY 0.617021 (125 1675);
PAINT SKYBLUE (125 1675);
FORCEPROP 1 LAST PACK_TYPE 0402
J 0
(75 1575);
DISPLAY 0.617021 (75 1575);
PAINT SKYBLUE (75 1575);
FORCEPROP 1 LAST TOLERANCE 5%
J 0
(150 1675);
DISPLAY 0.617021 (150 1675);
PAINT SKYBLUE (150 1675);
FORCEPROP 1 LASTPIN (50 1775) $PN 1
J 0
(62 1787);
DISPLAY 0.617021 (62 1787);
PAINT WHITE (62 1787);
FORCEPROP 1 LASTPIN (250 1775) $PN 2
J 0
(212 1787);
DISPLAY 0.617021 (212 1787);
PAINT WHITE (212 1787);
FORCEPROP 1 LAST LOCATION R6L8
J 0
(100 1825);
DISPLAY 0.617021 (100 1825);
PAINT AQUA (100 1825);
FORCEPROP 1 LAST MATERIAL CHIP
J 0
(150 1625);
DISPLAY 0.617021 (150 1625);
PAINT SKYBLUE (150 1625);
FORCEPROP 1 LAST PART_NUMBER G21497-005
J 0
(25 1725);
DISPLAY 0.617021 (25 1725);
PAINT BLUE (25 1725);
FORCEPROP 2 LAST CDS_LIB mstr_discrete
J 0
(150 1775);
DISPLAY 0.744681 (150 1775);
PAINT MONO (150 1775);
DISPLAY INVISIBLE (150 1775);
FORCEPROP 1 LAST PATH I30
J 0
(100 1925);
DISPLAY 0.978723 (100 1925);
PAINT WHITE (100 1925);
DISPLAY INVISIBLE (100 1925);
FORCEPROP 2 LAST SEC_TYPE 0402
J 0
(116 1975);
DISPLAY 1.021277 (116 1975);
PAINT ORANGE (116 1975);
DISPLAY INVISIBLE (116 1975);
FORCEPROP 2 LAST BOM_COST MEM_VRD_VTT_KLM
J 0
(110 1910);
DISPLAY 1.021277 (110 1910);
PAINT ORANGE (110 1910);
DISPLAY INVISIBLE (110 1910);
FORCEPROP 2 LAST CDS_LOCATION R6L8
J 0
(100 1825);
DISPLAY 0.617021 (100 1825);
PAINT AQUA (100 1825);
DISPLAY INVISIBLE (100 1825);
FORCEPROP 2 LAST SEC 1
J 0
(116 1975);
DISPLAY 0.680851 (116 1975);
PAINT MONO (116 1975);
DISPLAY INVISIBLE (116 1975);
FORCEPROP 2 LAST ROOM VTT_KLM_PWR_VR
J 0
(110 1860);
DISPLAY 1.021277 (110 1860);
PAINT ORANGE (110 1860);
DISPLAY INVISIBLE (110 1860);
FORCEADD MIC5166..1
(1575 1075);
FORCEPROP 2 LASTPIN (1275 975) $PN 6
J 2
(1265 985);
DISPLAY 0.617021 (1265 985);
PAINT ORANGE (1265 985);
FORCEPROP 2 LASTPIN (1275 825) $PN 2
J 2
(1265 835);
DISPLAY 0.617021 (1265 835);
PAINT ORANGE (1265 835);
FORCEPROP 1 LAST PART_NUMBER H55101-001
J 0
(1325 675);
DISPLAY 0.617021 (1325 675);
PAINT BLUE (1325 675);
FORCEPROP 2 LASTPIN (1875 875) $PN 3
J 0
(1885 885);
DISPLAY 0.617021 (1885 885);
PAINT ORANGE (1885 885);
FORCEPROP 2 LASTPIN (1875 925) $PN 8
J 0
(1885 935);
DISPLAY 0.617021 (1885 935);
PAINT ORANGE (1885 935);
FORCEPROP 2 LASTPIN (1875 775) $PN 11
J 0
(1885 785);
DISPLAY 0.617021 (1885 785);
PAINT ORANGE (1885 785);
FORCEPROP 2 LASTPIN (1275 1325) $PN 10
J 2
(1265 1335);
DISPLAY 0.617021 (1265 1335);
PAINT ORANGE (1265 1335);
FORCEPROP 2 LASTPIN (1275 1175) $PN 4
J 2
(1265 1185);
DISPLAY 0.617021 (1265 1185);
PAINT ORANGE (1265 1185);
FORCEPROP 2 LASTPIN (1275 1075) $PN 7
J 2
(1265 1085);
DISPLAY 0.617021 (1265 1085);
PAINT ORANGE (1265 1085);
FORCEPROP 1 LAST MATERIAL IC
J 0
(1325 1450);
DISPLAY 0.617021 (1325 1450);
PAINT SKYBLUE (1325 1450);
FORCEPROP 1 LAST LOCATION EU4A2
J 0
(1325 1500);
DISPLAY 0.617021 (1325 1500);
PAINT AQUA (1325 1500);
FORCEPROP 2 LASTPIN (1875 1325) $PN 9
J 0
(1885 1335);
DISPLAY 0.617021 (1885 1335);
PAINT ORANGE (1885 1335);
FORCEPROP 2 LASTPIN (1875 1225) $PN 1
J 0
(1885 1235);
DISPLAY 0.617021 (1885 1235);
PAINT ORANGE (1885 1235);
FORCEPROP 2 LASTPIN (1875 1025) $PN 5
J 0
(1885 1035);
DISPLAY 0.617021 (1885 1035);
PAINT ORANGE (1885 1035);
FORCEPROP 2 LAST CDS_LOCATION EU4A2
J 0
(1325 1500);
DISPLAY 0.617021 (1325 1500);
PAINT AQUA (1325 1500);
DISPLAY INVISIBLE (1325 1500);
FORCEPROP 2 LAST ROOM VTT_KLM_PWR_VR
J 0
(1325 1534);
DISPLAY 1.021277 (1325 1534);
PAINT ORANGE (1325 1534);
DISPLAY INVISIBLE (1325 1534);
FORCEPROP 2 LAST BOM_COST MEM_VRD_VTT_KLM
J 0
(1325 1582);
DISPLAY 1.021277 (1325 1582);
PAINT ORANGE (1325 1582);
DISPLAY INVISIBLE (1325 1582);
FORCEPROP 2 LAST SEC_TYPE DFN
J 0
(1332 1543);
DISPLAY 1.021277 (1332 1543);
PAINT ORANGE (1332 1543);
DISPLAY INVISIBLE (1332 1543);
FORCEPROP 2 LAST SEC 1
J 0
(1332 1543);
DISPLAY 0.680851 (1332 1543);
PAINT MONO (1332 1543);
DISPLAY INVISIBLE (1332 1543);
FORCEPROP 1 LAST PACK_TYPE DFN
J 0
(1325 1550);
PAINT SKYBLUE (1325 1550);
DISPLAY INVISIBLE (1325 1550);
FORCEPROP 1 LAST CDS_LMAN_SYM_OUTLINE -250,350,250,-350
J 0
(1575 1075);
DISPLAY 0.468085 (1575 1075);
PAINT GREEN (1575 1075);
DISPLAY INVISIBLE (1575 1075);
FORCEPROP 2 LAST CDS_LIB mstr_vreg
J 0
(1575 1075);
PAINT ORANGE (1575 1075);
DISPLAY INVISIBLE (1575 1075);
FORCEPROP 1 LAST PATH I31
J 0
(1775 1450);
PAINT GREEN (1775 1450);
DISPLAY INVISIBLE (1775 1450);
FORCEADD RES..2
R 1
(-675 1575);
FORCEPROP 1 LAST MATERIAL CHIP
J 0
(-750 1340);
DISPLAY 0.617021 (-750 1340);
PAINT SKYBLUE (-750 1340);
FORCEPROP 1 LAST TOLERANCE 5%
J 0
(-825 1520);
DISPLAY 0.617021 (-825 1520);
PAINT SKYBLUE (-825 1520);
FORCEPROP 1 LAST VALUE 0.0
J 0
(-750 1520);
DISPLAY 0.617021 (-750 1520);
PAINT SKYBLUE (-750 1520);
FORCEPROP 1 LASTPIN (-775 1575) $PN 1
R 1
J 0
(-737 1580);
DISPLAY 0.617021 (-737 1580);
PAINT WHITE (-737 1580);
FORCEPROP 1 LAST LOCATION R6L6
J 0
(-700 1620);
DISPLAY 0.617021 (-700 1620);
PAINT AQUA (-700 1620);
FORCEPROP 1 LASTPIN (-575 1575) $PN 2
R 1
J 0
(-585 1580);
DISPLAY 0.617021 (-585 1580);
PAINT WHITE (-585 1580);
FORCEPROP 1 LAST WATTAGE 1/16W
J 0
(-650 1515);
DISPLAY 0.617021 (-650 1515);
PAINT SKYBLUE (-650 1515);
FORCEPROP 1 LAST PART_NUMBER G21497-005
J 0
(-775 1465);
DISPLAY 0.617021 (-775 1465);
PAINT BLUE (-775 1465);
FORCEPROP 1 LAST PACK_TYPE 0402
J 0
(-450 1515);
DISPLAY 0.617021 (-450 1515);
PAINT SKYBLUE (-450 1515);
FORCEPROP 1 LAST PATH I34
R 1
J 0
(-850 1625);
DISPLAY 0.978723 (-850 1625);
PAINT WHITE (-850 1625);
DISPLAY INVISIBLE (-850 1625);
FORCEPROP 2 LAST CDS_LIB mstr_discrete
R 1
J 0
(-675 1575);
PAINT ORANGE (-675 1575);
DISPLAY INVISIBLE (-675 1575);
FORCEPROP 2 LAST SEC_TYPE 0402
J 0
(-694 1665);
DISPLAY 1.021277 (-694 1665);
PAINT ORANGE (-694 1665);
DISPLAY INVISIBLE (-694 1665);
FORCEPROP 2 LAST BOM_COST MEM_VRD_VTT_KLM
J 0
(-700 1725);
DISPLAY 1.021277 (-700 1725);
PAINT ORANGE (-700 1725);
DISPLAY INVISIBLE (-700 1725);
FORCEPROP 2 LAST CDS_LOCATION R6L6
J 0
(-700 1620);
DISPLAY 0.617021 (-700 1620);
PAINT AQUA (-700 1620);
DISPLAY INVISIBLE (-700 1620);
FORCEPROP 2 LAST NO_XNET_CONNECTION 1
J 0
(-700 1650);
PAINT MONO (-700 1650);
DISPLAY INVISIBLE (-700 1650);
FORCEPROP 2 LAST SEC 1
J 0
(-694 1665);
DISPLAY 0.680851 (-694 1665);
PAINT MONO (-694 1665);
DISPLAY INVISIBLE (-694 1665);
FORCEPROP 2 LAST ROOM VTT_KLM_PWR_VR
J 0
(-700 1675);
DISPLAY 1.021277 (-700 1675);
PAINT ORANGE (-700 1675);
DISPLAY INVISIBLE (-700 1675);
FORCEADD PVDDQ_KLM..1
(-1425 2800);
FORCEPROP 3 LASTPIN (-1425 2750) SIG_NAME PVDDQ_KLM\g
J 0
(-1415 2760);
DISPLAY 0.659574 (-1415 2760);
PAINT MONO (-1415 2760);
DISPLAY INVISIBLE (-1415 2760);
FORCEPROP 2 LAST CDS_LIB mstr_symbols
J 0
(-1425 2800);
PAINT ORANGE (-1425 2800);
DISPLAY INVISIBLE (-1425 2800);
FORCEPROP 1 LAST BODY_TYPE PLUMBING
J 0
(-1470 2757);
DISPLAY 0.340426 (-1470 2757);
PAINT GREEN (-1470 2757);
DISPLAY INVISIBLE (-1470 2757);
FORCEPROP 1 LAST PATH I35
J 0
(-1375 2825);
DISPLAY 0.872340 (-1375 2825);
PAINT AQUA (-1375 2825);
DISPLAY INVISIBLE (-1375 2825);
FORCEPROP 1 LAST HDL_POWER PVDDQ_KLM
J 1
(-1425 2850);
DISPLAY 0.872340 (-1425 2850);
PAINT GREEN (-1425 2850);
DISPLAY INVISIBLE (-1425 2850);
FORCEPROP 1 LAST VOLTAGE 1.2V
J 0
(-1470 2757);
DISPLAY 0.340426 (-1470 2757);
PAINT SKYBLUE (-1470 2757);
DISPLAY INVISIBLE (-1470 2757);
FORCEADD RES..2
R 2
(-300 675);
FORCEPROP 1 LAST PART_NUMBER G21796-021
J 2
(-340 550);
DISPLAY 0.617021 (-340 550);
PAINT BLUE (-340 550);
FORCEPROP 1 LAST PACK_TYPE 0402
J 2
(-340 500);
DISPLAY 0.617021 (-340 500);
PAINT SKYBLUE (-340 500);
FORCEPROP 1 LAST WATTAGE 1/16W
J 2
(-340 650);
DISPLAY 0.617021 (-340 650);
PAINT SKYBLUE (-340 650);
FORCEPROP 1 LAST TOLERANCE 1%
J 2
(-345 700);
DISPLAY 0.617021 (-345 700);
PAINT SKYBLUE (-345 700);
FORCEPROP 1 LAST MATERIAL EMPTY
J 2
(-340 600);
DISPLAY 0.617021 (-340 600);
PAINT RED (-340 600);
FORCEPROP 1 LASTPIN (-300 575) $PN 2
J 2
(-305 585);
DISPLAY 0.617021 (-305 585);
PAINT WHITE (-305 585);
FORCEPROP 1 LASTPIN (-300 775) $PN 1
J 2
(-305 737);
DISPLAY 0.617021 (-305 737);
PAINT WHITE (-305 737);
FORCEPROP 1 LAST VALUE 1.0M
J 2
(-345 750);
DISPLAY 0.617021 (-345 750);
PAINT SKYBLUE (-345 750);
FORCEPROP 1 LAST LOCATION R6L5
J 2
(-345 800);
DISPLAY 0.617021 (-345 800);
PAINT AQUA (-345 800);
FORCEPROP 2 LAST CDS_LIB mstr_discrete
J 0
(-300 675);
PAINT ORANGE (-300 675);
DISPLAY INVISIBLE (-300 675);
FORCEPROP 2 LAST BOM_COST MEM_VRD_VTT_KLM
J 0
(-335 890);
DISPLAY 1.021277 (-335 890);
PAINT ORANGE (-335 890);
DISPLAY INVISIBLE (-335 890);
FORCEPROP 2 LAST SEC_TYPE 0402
J 0
(-329 905);
DISPLAY 1.021277 (-329 905);
PAINT ORANGE (-329 905);
DISPLAY INVISIBLE (-329 905);
FORCEPROP 2 LAST SEC 1
J 0
(-329 905);
DISPLAY 0.680851 (-329 905);
PAINT MONO (-329 905);
DISPLAY INVISIBLE (-329 905);
FORCEPROP 2 LAST CDS_LOCATION R6L5
J 2
(-345 800);
DISPLAY 0.617021 (-345 800);
PAINT AQUA (-345 800);
DISPLAY INVISIBLE (-345 800);
FORCEPROP 1 LAST PATH I37
J 2
(-350 850);
DISPLAY 0.978723 (-350 850);
PAINT WHITE (-350 850);
DISPLAY INVISIBLE (-350 850);
FORCEPROP 2 LAST ROOM VTT_KLM_PWR_VR
J 0
(-335 840);
DISPLAY 1.021277 (-335 840);
PAINT ORANGE (-335 840);
DISPLAY INVISIBLE (-335 840);
FORCEADD RES..1
(-500 150);
FORCEPROP 1 LAST MATERIAL CHIP
J 0
(-800 -25);
DISPLAY 0.617021 (-800 -25);
PAINT SKYBLUE (-800 -25);
FORCEPROP 1 LAST PACK_TYPE 0402
J 0
(-575 -25);
DISPLAY 0.617021 (-575 -25);
PAINT SKYBLUE (-575 -25);
FORCEPROP 1 LASTPIN (-600 150) $PN 1
J 0
(-588 162);
DISPLAY 0.617021 (-588 162);
PAINT WHITE (-588 162);
FORCEPROP 1 LAST WATTAGE 1/16W
J 2
(-650 50);
DISPLAY 0.617021 (-650 50);
PAINT SKYBLUE (-650 50);
FORCEPROP 1 LAST VALUE 0.0
J 2
(-525 50);
DISPLAY 0.617021 (-525 50);
PAINT SKYBLUE (-525 50);
FORCEPROP 1 LAST PART_NUMBER G21497-005
J 0
(-550 250);
DISPLAY 0.617021 (-550 250);
PAINT BLUE (-550 250);
FORCEPROP 1 LAST LOCATION R4A3
J 0
(-550 200);
DISPLAY 0.617021 (-550 200);
PAINT AQUA (-550 200);
FORCEPROP 1 LAST TOLERANCE 5%
J 0
(-500 50);
DISPLAY 0.617021 (-500 50);
PAINT SKYBLUE (-500 50);
FORCEPROP 1 LASTPIN (-400 150) $PN 2
J 0
(-438 162);
DISPLAY 0.617021 (-438 162);
PAINT WHITE (-438 162);
FORCEPROP 2 LAST SEC_TYPE 0402
J 0
(-550 350);
DISPLAY 1.021277 (-550 350);
PAINT ORANGE (-550 350);
DISPLAY INVISIBLE (-550 350);
FORCEPROP 2 LAST BOM_COST MEM_VRD_VTT_KLM
J 0
(-530 355);
DISPLAY 1.021277 (-530 355);
PAINT ORANGE (-530 355);
DISPLAY INVISIBLE (-530 355);
FORCEPROP 2 LAST SEC 1
J 0
(-550 350);
DISPLAY 0.680851 (-550 350);
PAINT MONO (-550 350);
DISPLAY INVISIBLE (-550 350);
FORCEPROP 2 LAST CDS_LOCATION R4A3
J 0
(-550 200);
DISPLAY 0.617021 (-550 200);
PAINT AQUA (-550 200);
DISPLAY INVISIBLE (-550 200);
FORCEPROP 1 LAST PATH I38
J 0
(-550 300);
DISPLAY 0.978723 (-550 300);
PAINT WHITE (-550 300);
DISPLAY INVISIBLE (-550 300);
FORCEPROP 2 LAST ROOM VTT_KLM_PWR_VR
J 0
(-530 305);
DISPLAY 1.021277 (-530 305);
PAINT ORANGE (-530 305);
DISPLAY INVISIBLE (-530 305);
FORCEPROP 2 LAST CDS_LIB mstr_discrete
J 0
(-500 150);
PAINT ORANGE (-500 150);
DISPLAY INVISIBLE (-500 150);
FORCEADD CAP..1
R 2
(-350 -375);
FORCEPROP 1 LAST PACK_TYPE 0402LF
J 2
(-400 -425);
DISPLAY 0.617021 (-400 -425);
PAINT SKYBLUE (-400 -425);
FORCEPROP 1 LAST VALUE 1000PF
J 2
(-400 -325);
DISPLAY 0.617021 (-400 -325);
PAINT SKYBLUE (-400 -325);
FORCEPROP 1 LAST LOCATION C4A6
J 2
(-400 -275);
DISPLAY 0.617021 (-400 -275);
PAINT AQUA (-400 -275);
FORCEPROP 1 LAST MATERIAL EMPTY
J 2
(-400 -475);
DISPLAY 0.617021 (-400 -475);
PAINT RED (-400 -475);
FORCEPROP 1 LAST TOLERANCE 10%
J 2
(-400 -425);
DISPLAY 0.617021 (-400 -425);
PAINT SKYBLUE (-400 -425);
FORCEPROP 1 LAST VOLTAGE 50V
J 2
(-400 -375);
DISPLAY 0.617021 (-400 -375);
PAINT SKYBLUE (-400 -375);
FORCEPROP 1 LASTPIN (-350 -475) $PN 2
J 2
(-360 -495);
DISPLAY 0.617021 (-360 -495);
PAINT WHITE (-360 -495);
FORCEPROP 1 LASTPIN (-350 -275) $PN 1
J 2
(-360 -295);
DISPLAY 0.617021 (-360 -295);
PAINT WHITE (-360 -295);
FORCEPROP 1 LAST PART_NUMBER A36096-046
J 2
(-400 -525);
DISPLAY 0.659574 (-400 -525);
PAINT BLUE (-400 -525);
DISPLAY INVISIBLE (-400 -525);
FORCEPROP 2 LAST CDS_LIB mstr_discrete
J 0
(-350 -375);
PAINT ORANGE (-350 -375);
DISPLAY INVISIBLE (-350 -375);
FORCEPROP 2 LAST CDS_LOCATION C4A6
J 2
(-400 -275);
DISPLAY 0.617021 (-400 -275);
PAINT AQUA (-400 -275);
DISPLAY INVISIBLE (-400 -275);
FORCEPROP 2 LAST BOM_COST MEM_VRD_VTT_KLM
J 0
(-385 -170);
DISPLAY 1.021277 (-385 -170);
PAINT ORANGE (-385 -170);
DISPLAY INVISIBLE (-385 -170);
FORCEPROP 2 LAST SEC_TYPE 0402LF
J 0
(-379 -155);
DISPLAY 1.021277 (-379 -155);
PAINT ORANGE (-379 -155);
DISPLAY INVISIBLE (-379 -155);
FORCEPROP 2 LAST SEC 1
J 0
(-379 -155);
DISPLAY 0.680851 (-379 -155);
PAINT MONO (-379 -155);
DISPLAY INVISIBLE (-379 -155);
FORCEPROP 1 LAST PATH I39
J 2
(-400 -225);
DISPLAY 0.978723 (-400 -225);
PAINT WHITE (-400 -225);
DISPLAY INVISIBLE (-400 -225);
FORCEPROP 2 LAST ROOM VTT_KLM_PWR_VR
J 0
(-385 -220);
DISPLAY 1.021277 (-385 -220);
PAINT ORANGE (-385 -220);
DISPLAY INVISIBLE (-385 -220);
FORCEADD GND..1
(-350 -600);
FORCEPROP 3 LASTPIN (-350 -550) SIG_NAME GND\g
J 0
(-340 -540);
DISPLAY 0.659574 (-340 -540);
PAINT MONO (-340 -540);
DISPLAY INVISIBLE (-340 -540);
FORCEPROP 2 LAST CDS_LIB mstr_symbols
J 0
(-350 -600);
PAINT MONO (-350 -600);
DISPLAY INVISIBLE (-350 -600);
FORCEPROP 1 LAST SIZE 1B
J 0
(-275 -650);
DISPLAY 0.893617 (-275 -650);
PAINT GREEN (-275 -650);
DISPLAY INVISIBLE (-275 -650);
FORCEPROP 1 LAST BODY_TYPE PLUMBING
J 0
(-395 -643);
DISPLAY 0.340426 (-395 -643);
PAINT GREEN (-395 -643);
DISPLAY INVISIBLE (-395 -643);
FORCEPROP 1 LAST PATH I40
J 0
(-275 -600);
DISPLAY 0.872340 (-275 -600);
PAINT AQUA (-275 -600);
DISPLAY INVISIBLE (-275 -600);
FORCEPROP 1 LAST VOLTAGE 0.0V
J 0
(-395 -643);
DISPLAY 0.340426 (-395 -643);
PAINT SKYBLUE (-395 -643);
DISPLAY INVISIBLE (-395 -643);
FORCEPROP 1 LAST HDL_POWER GND
J 0
(-350 -450);
DISPLAY 0.893617 (-350 -450);
PAINT GREEN (-350 -450);
DISPLAY INVISIBLE (-350 -450);
FORCEADD OFFPAGE..1
(-1400 150);
FORCEPROP 2 LAST $XR0 226 
J 0
(-1652 150);
DISPLAY 0.638298 (-1652 150);
PAINT MONO (-1652 150);
FORCEPROP 2 LAST PATH I41
J 0
(-1662 188);
DISPLAY 1.021277 (-1662 188);
PAINT ORANGE (-1662 188);
DISPLAY INVISIBLE (-1662 188);
FORCEPROP 1 LAST COMMENT_BODY TRUE
J 0
(-1275 50);
DISPLAY 0.872340 (-1275 50);
PAINT GREEN (-1275 50);
DISPLAY INVISIBLE (-1275 50);
FORCEPROP 1 LAST OFFPAGE TRUE
J 0
(-1075 25);
DISPLAY 0.872340 (-1075 25);
PAINT GREEN (-1075 25);
DISPLAY INVISIBLE (-1075 25);
FORCEPROP 2 LAST CDS_LIB mstr_standard
J 0
(-1400 150);
DISPLAY 0.744681 (-1400 150);
PAINT MONO (-1400 150);
DISPLAY INVISIBLE (-1400 150);
FORCEADD P3V3..1
(-375 2075);
FORCEPROP 3 LASTPIN (-375 2025) SIG_NAME P3V3\g
J 0
(-365 2035);
DISPLAY 0.659574 (-365 2035);
PAINT MONO (-365 2035);
DISPLAY INVISIBLE (-365 2035);
FORCEPROP 1 LAST HDL_POWER P3V3
J 0
(-700 1950);
DISPLAY 0.872340 (-700 1950);
PAINT ORANGE (-700 1950);
DISPLAY INVISIBLE (-700 1950);
FORCEPROP 1 LAST VOLTAGE 3.3V
J 0
(-420 2032);
DISPLAY 0.340426 (-420 2032);
PAINT SKYBLUE (-420 2032);
DISPLAY INVISIBLE (-420 2032);
FORCEPROP 1 LAST BODY_TYPE PLUMBING
J 0
(-420 2032);
DISPLAY 0.340426 (-420 2032);
PAINT GREEN (-420 2032);
DISPLAY INVISIBLE (-420 2032);
FORCEPROP 1 LAST PATH I42
J 0
(-330 2077);
DISPLAY 0.340426 (-330 2077);
PAINT GREEN (-330 2077);
DISPLAY INVISIBLE (-330 2077);
FORCEPROP 2 LAST CDS_LIB mstr_symbols
J 0
(-375 2075);
PAINT ORANGE (-375 2075);
DISPLAY INVISIBLE (-375 2075);
FORCEPROP 1 LAST SIZE 1B
J 0
(-330 2097);
DISPLAY 0.340426 (-330 2097);
PAINT GREEN (-330 2097);
DISPLAY INVISIBLE (-330 2097);
FORCEADD P3V3..1
(3500 2325);
FORCEPROP 3 LASTPIN (3500 2275) SIG_NAME P3V3\g
J 0
(3510 2285);
DISPLAY 0.659574 (3510 2285);
PAINT MONO (3510 2285);
DISPLAY INVISIBLE (3510 2285);
FORCEPROP 1 LAST HDL_POWER P3V3
J 0
(3175 2200);
DISPLAY 0.872340 (3175 2200);
PAINT ORANGE (3175 2200);
DISPLAY INVISIBLE (3175 2200);
FORCEPROP 1 LAST BODY_TYPE PLUMBING
J 0
(3455 2282);
DISPLAY 0.340426 (3455 2282);
PAINT GREEN (3455 2282);
DISPLAY INVISIBLE (3455 2282);
FORCEPROP 1 LAST VOLTAGE 3.3V
J 0
(3455 2282);
DISPLAY 0.340426 (3455 2282);
PAINT SKYBLUE (3455 2282);
DISPLAY INVISIBLE (3455 2282);
FORCEPROP 1 LAST PATH I43
J 0
(3545 2327);
DISPLAY 0.340426 (3545 2327);
PAINT GREEN (3545 2327);
DISPLAY INVISIBLE (3545 2327);
FORCEPROP 2 LAST CDS_LIB mstr_symbols
J 0
(3500 2325);
PAINT ORANGE (3500 2325);
DISPLAY INVISIBLE (3500 2325);
FORCEPROP 1 LAST SIZE 1B
J 0
(3545 2347);
DISPLAY 0.340426 (3545 2347);
PAINT GREEN (3545 2347);
DISPLAY INVISIBLE (3545 2347);
FORCEADD GND..1
(375 775);
FORCEPROP 3 LASTPIN (375 825) SIG_NAME GND\g
J 0
(385 835);
DISPLAY 0.659574 (385 835);
PAINT MONO (385 835);
DISPLAY INVISIBLE (385 835);
FORCEPROP 1 LAST SIZE 1B
J 0
(450 725);
DISPLAY 0.872340 (450 725);
PAINT AQUA (450 725);
DISPLAY INVISIBLE (450 725);
FORCEPROP 1 LAST BODY_TYPE PLUMBING
J 0
(330 732);
DISPLAY 0.340426 (330 732);
PAINT GREEN (330 732);
DISPLAY INVISIBLE (330 732);
FORCEPROP 1 LAST VOLTAGE 0.0V
J 0
(330 732);
DISPLAY 0.340426 (330 732);
PAINT SKYBLUE (330 732);
DISPLAY INVISIBLE (330 732);
FORCEPROP 1 LAST HDL_POWER GND
J 0
(375 925);
DISPLAY 0.872340 (375 925);
PAINT GREEN (375 925);
DISPLAY INVISIBLE (375 925);
FORCEPROP 2 LAST CDS_LIB mstr_symbols
J 0
(375 775);
PAINT ORANGE (375 775);
DISPLAY INVISIBLE (375 775);
FORCEPROP 1 LAST PATH I45
J 0
(450 775);
DISPLAY 0.872340 (450 775);
PAINT AQUA (450 775);
DISPLAY INVISIBLE (450 775);
FORCEADD CAP..1
(375 975);
FORCEPROP 1 LASTPIN (375 875) $PN 2
J 0
(385 855);
DISPLAY 0.617021 (385 855);
PAINT ORANGE (385 855);
FORCEPROP 1 LAST MATERIAL X6S
J 0
(425 875);
DISPLAY 0.617021 (425 875);
PAINT SKYBLUE (425 875);
FORCEPROP 1 LAST VOLTAGE 6.3V
J 0
(425 975);
DISPLAY 0.617021 (425 975);
PAINT SKYBLUE (425 975);
FORCEPROP 1 LAST PACK_TYPE 0603
J 0
(425 775);
DISPLAY 0.617021 (425 775);
PAINT SKYBLUE (425 775);
FORCEPROP 1 LAST TOLERANCE 10%
J 0
(425 925);
DISPLAY 0.617021 (425 925);
PAINT SKYBLUE (425 925);
FORCEPROP 1 LAST PART_NUMBER E15431-003
J 0
(425 825);
DISPLAY 0.617021 (425 825);
PAINT BLUE (425 825);
FORCEPROP 1 LASTPIN (375 1075) $PN 1
J 0
(385 1055);
DISPLAY 0.617021 (385 1055);
PAINT ORANGE (385 1055);
FORCEPROP 1 LAST VALUE 4.7UF
J 0
(425 1025);
DISPLAY 0.617021 (425 1025);
PAINT SKYBLUE (425 1025);
FORCEPROP 1 LAST LOCATION C4A7
J 0
(425 1075);
DISPLAY 0.617021 (425 1075);
PAINT AQUA (425 1075);
FORCEPROP 2 LAST CDS_LIB mstr_discrete
J 0
(375 975);
PAINT ORANGE (375 975);
DISPLAY INVISIBLE (375 975);
FORCEPROP 0 LAST ROOM VTT_KLM_PWR_VR
J 0
(425 1175);
DISPLAY 1.021277 (425 1175);
PAINT ORANGE (425 1175);
DISPLAY INVISIBLE (425 1175);
FORCEPROP 1 LAST PATH I46
J 0
(425 1125);
DISPLAY 0.978723 (425 1125);
PAINT WHITE (425 1125);
DISPLAY INVISIBLE (425 1125);
FORCEPROP 2 LAST CDS_LOCATION C4A7
J 0
(425 1075);
DISPLAY 0.617021 (425 1075);
PAINT AQUA (425 1075);
DISPLAY INVISIBLE (425 1075);
FORCEPROP 2 LAST SEC 1
J 0
(425 1175);
DISPLAY 0.680851 (425 1175);
PAINT MONO (425 1175);
DISPLAY INVISIBLE (425 1175);
FORCEPROP 2 LAST SEC_TYPE 0603
J 0
(425 1175);
DISPLAY 1.021277 (425 1175);
PAINT ORANGE (425 1175);
DISPLAY INVISIBLE (425 1175);
FORCEADD CAP_A..1
(3025 3425);
FORCEPROP 1 LASTPIN (3025 3525) $PN 1
J 0
(3035 3505);
DISPLAY 0.617021 (3035 3505);
PAINT ORANGE (3035 3505);
FORCEPROP 1 LASTPIN (3025 3325) $PN 2
J 0
(3035 3305);
DISPLAY 0.617021 (3035 3305);
PAINT ORANGE (3035 3305);
FORCEPROP 1 LAST MATERIAL X5R
J 0
(3075 3325);
DISPLAY 0.617021 (3075 3325);
PAINT SKYBLUE (3075 3325);
FORCEPROP 1 LAST VOLTAGE 4V
J 0
(3075 3425);
DISPLAY 0.617021 (3075 3425);
PAINT SKYBLUE (3075 3425);
FORCEPROP 1 LAST PACK_TYPE 0603V
J 0
(3075 3225);
DISPLAY 0.617021 (3075 3225);
PAINT SKYBLUE (3075 3225);
FORCEPROP 1 LAST TOLERANCE 20%
J 0
(3075 3375);
DISPLAY 0.617021 (3075 3375);
PAINT SKYBLUE (3075 3375);
FORCEPROP 1 LAST VALUE 47UF
J 0
(3075 3475);
DISPLAY 0.617021 (3075 3475);
PAINT SKYBLUE (3075 3475);
FORCEPROP 1 LAST LOCATION C8M12
J 0
(3075 3525);
DISPLAY 0.617021 (3075 3525);
PAINT AQUA (3075 3525);
FORCEPROP 1 LAST PART_NUMBER 602433-106
J 0
(3075 3275);
DISPLAY 0.617021 (3075 3275);
PAINT BLUE (3075 3275);
FORCEPROP 2 LAST CDS_LIB dev_discrete
J 0
(3025 3425);
PAINT ORANGE (3025 3425);
DISPLAY INVISIBLE (3025 3425);
FORCEPROP 2 LAST CDS_LOCATION C8M12
J 0
(3075 3525);
DISPLAY 0.617021 (3075 3525);
PAINT AQUA (3075 3525);
DISPLAY INVISIBLE (3075 3525);
FORCEPROP 2 LAST CDS_SEC 1
J 0
(3075 3575);
PAINT ORANGE (3075 3575);
DISPLAY INVISIBLE (3075 3575);
FORCEPROP 1 LAST PATH I47
J 0
(3075 3575);
DISPLAY 0.978723 (3075 3575);
PAINT WHITE (3075 3575);
DISPLAY INVISIBLE (3075 3575);
FORCEPROP 2 LAST SEC_TYPE 0603V
J 0
(3075 3625);
DISPLAY 1.021277 (3075 3625);
PAINT ORANGE (3075 3625);
DISPLAY INVISIBLE (3075 3625);
FORCEPROP 2 LAST SEC 1
J 0
(3075 3625);
DISPLAY 0.680851 (3075 3625);
PAINT MONO (3075 3625);
DISPLAY INVISIBLE (3075 3625);
FORCEADD CAP_A..1
(3375 3425);
FORCEPROP 1 LAST PACK_TYPE 0603V
J 0
(3425 3225);
DISPLAY 0.617021 (3425 3225);
PAINT SKYBLUE (3425 3225);
FORCEPROP 1 LAST MATERIAL X5R
J 0
(3425 3325);
DISPLAY 0.617021 (3425 3325);
PAINT SKYBLUE (3425 3325);
FORCEPROP 1 LASTPIN (3375 3325) $PN 2
J 0
(3385 3305);
DISPLAY 0.617021 (3385 3305);
PAINT ORANGE (3385 3305);
FORCEPROP 1 LAST VOLTAGE 4V
J 0
(3425 3425);
DISPLAY 0.617021 (3425 3425);
PAINT SKYBLUE (3425 3425);
FORCEPROP 1 LASTPIN (3375 3525) $PN 1
J 0
(3385 3505);
DISPLAY 0.617021 (3385 3505);
PAINT ORANGE (3385 3505);
FORCEPROP 1 LAST TOLERANCE 20%
J 0
(3425 3375);
DISPLAY 0.617021 (3425 3375);
PAINT SKYBLUE (3425 3375);
FORCEPROP 1 LAST VALUE 47UF
J 0
(3425 3475);
DISPLAY 0.617021 (3425 3475);
PAINT SKYBLUE (3425 3475);
FORCEPROP 1 LAST LOCATION C8L3
J 0
(3425 3525);
DISPLAY 0.617021 (3425 3525);
PAINT AQUA (3425 3525);
FORCEPROP 1 LAST PART_NUMBER 602433-106
J 0
(3425 3275);
DISPLAY 0.617021 (3425 3275);
PAINT BLUE (3425 3275);
FORCEPROP 2 LAST CDS_LOCATION C8L3
J 0
(3425 3525);
DISPLAY 0.617021 (3425 3525);
PAINT AQUA (3425 3525);
DISPLAY INVISIBLE (3425 3525);
FORCEPROP 2 LAST CDS_LIB dev_discrete
J 0
(3375 3425);
PAINT ORANGE (3375 3425);
DISPLAY INVISIBLE (3375 3425);
FORCEPROP 2 LAST CDS_SEC 1
J 0
(3425 3575);
PAINT ORANGE (3425 3575);
DISPLAY INVISIBLE (3425 3575);
FORCEPROP 1 LAST PATH I48
J 0
(3425 3575);
DISPLAY 0.978723 (3425 3575);
PAINT WHITE (3425 3575);
DISPLAY INVISIBLE (3425 3575);
FORCEPROP 2 LAST SEC_TYPE 0603V
J 0
(3425 3625);
DISPLAY 1.021277 (3425 3625);
PAINT ORANGE (3425 3625);
DISPLAY INVISIBLE (3425 3625);
FORCEPROP 2 LAST SEC 1
J 0
(3425 3625);
DISPLAY 0.680851 (3425 3625);
PAINT MONO (3425 3625);
DISPLAY INVISIBLE (3425 3625);
FORCEADD CAP_A..1
(3775 3425);
FORCEPROP 1 LASTPIN (3775 3325) $PN 2
J 0
(3785 3305);
DISPLAY 0.617021 (3785 3305);
PAINT ORANGE (3785 3305);
FORCEPROP 1 LASTPIN (3775 3525) $PN 1
J 0
(3785 3505);
DISPLAY 0.617021 (3785 3505);
PAINT ORANGE (3785 3505);
FORCEPROP 1 LAST TOLERANCE 20%
J 0
(3825 3375);
DISPLAY 0.617021 (3825 3375);
PAINT SKYBLUE (3825 3375);
FORCEPROP 1 LAST PACK_TYPE 0603V
J 0
(3825 3225);
DISPLAY 0.617021 (3825 3225);
PAINT SKYBLUE (3825 3225);
FORCEPROP 1 LAST MATERIAL X5R
J 0
(3825 3325);
DISPLAY 0.617021 (3825 3325);
PAINT SKYBLUE (3825 3325);
FORCEPROP 1 LAST VOLTAGE 4V
J 0
(3825 3425);
DISPLAY 0.617021 (3825 3425);
PAINT SKYBLUE (3825 3425);
FORCEPROP 1 LAST VALUE 47UF
J 0
(3825 3475);
DISPLAY 0.617021 (3825 3475);
PAINT SKYBLUE (3825 3475);
FORCEPROP 1 LAST LOCATION C8L4
J 0
(3825 3525);
DISPLAY 0.617021 (3825 3525);
PAINT AQUA (3825 3525);
FORCEPROP 1 LAST PART_NUMBER 602433-106
J 0
(3825 3275);
DISPLAY 0.617021 (3825 3275);
PAINT BLUE (3825 3275);
FORCEPROP 2 LAST CDS_LIB dev_discrete
J 0
(3775 3425);
PAINT ORANGE (3775 3425);
DISPLAY INVISIBLE (3775 3425);
FORCEPROP 2 LAST CDS_LOCATION C8L4
J 0
(3825 3525);
DISPLAY 0.617021 (3825 3525);
PAINT AQUA (3825 3525);
DISPLAY INVISIBLE (3825 3525);
FORCEPROP 2 LAST CDS_SEC 1
J 0
(3825 3575);
PAINT ORANGE (3825 3575);
DISPLAY INVISIBLE (3825 3575);
FORCEPROP 1 LAST PATH I49
J 0
(3825 3575);
DISPLAY 0.978723 (3825 3575);
PAINT WHITE (3825 3575);
DISPLAY INVISIBLE (3825 3575);
FORCEPROP 2 LAST SEC_TYPE 0603V
J 0
(3825 3625);
DISPLAY 1.021277 (3825 3625);
PAINT ORANGE (3825 3625);
DISPLAY INVISIBLE (3825 3625);
FORCEPROP 2 LAST SEC 1
J 0
(3825 3625);
DISPLAY 0.680851 (3825 3625);
PAINT MONO (3825 3625);
DISPLAY INVISIBLE (3825 3625);
FORCEADD RES..1
(4150 1850);
FORCEPROP 1 LASTPIN (4050 1850) $PN 1
J 0
(4062 1862);
DISPLAY 0.617021 (4062 1862);
PAINT ORANGE (4062 1862);
FORCEPROP 1 LAST WATTAGE 1/16W
J 2
(4125 1700);
DISPLAY 0.617021 (4125 1700);
PAINT SKYBLUE (4125 1700);
FORCEPROP 1 LAST VALUE 33.2
J 2
(4125 1750);
DISPLAY 0.617021 (4125 1750);
PAINT SKYBLUE (4125 1750);
FORCEPROP 1 LAST TOLERANCE 1%
J 0
(4150 1750);
DISPLAY 0.617021 (4150 1750);
PAINT SKYBLUE (4150 1750);
FORCEPROP 1 LAST MATERIAL CHIP
J 0
(4150 1700);
DISPLAY 0.617021 (4150 1700);
PAINT SKYBLUE (4150 1700);
FORCEPROP 1 LAST LOCATION R4A4
J 0
(4100 1900);
DISPLAY 0.617021 (4100 1900);
PAINT AQUA (4100 1900);
FORCEPROP 1 LASTPIN (4250 1850) $PN 2
J 0
(4212 1862);
DISPLAY 0.617021 (4212 1862);
PAINT ORANGE (4212 1862);
FORCEPROP 1 LAST PART_NUMBER G21796-074
J 0
(4100 1950);
DISPLAY 0.617021 (4100 1950);
PAINT BLUE (4100 1950);
FORCEPROP 1 LAST PACK_TYPE 0402
J 0
(4400 1700);
DISPLAY 0.617021 (4400 1700);
PAINT SKYBLUE (4400 1700);
FORCEPROP 1 LAST PATH I51
J 0
(4100 2000);
DISPLAY 0.978723 (4100 2000);
PAINT WHITE (4100 2000);
DISPLAY INVISIBLE (4100 2000);
FORCEPROP 2 LAST CDS_LOCATION R4A4
J 0
(4100 1900);
DISPLAY 0.617021 (4100 1900);
PAINT AQUA (4100 1900);
DISPLAY INVISIBLE (4100 1900);
FORCEPROP 2 LAST CDS_LIB mstr_discrete
J 0
(4150 1850);
PAINT MONO (4150 1850);
DISPLAY INVISIBLE (4150 1850);
FORCEPROP 2 LAST SEC 1
J 0
(4100 2050);
DISPLAY 0.680851 (4100 2050);
PAINT MONO (4100 2050);
DISPLAY INVISIBLE (4100 2050);
FORCEPROP 2 LAST SEC_TYPE 0402
J 0
(4100 2050);
DISPLAY 1.021277 (4100 2050);
PAINT ORANGE (4100 2050);
DISPLAY INVISIBLE (4100 2050);
FORCEADD RES..1
R 1
(4800 975);
FORCEPROP 1 LAST VALUE 51.1
R 1
J 2
(4900 950);
DISPLAY 0.617021 (4900 950);
PAINT SKYBLUE (4900 950);
FORCEPROP 1 LAST WATTAGE 1/16W
R 1
J 2
(4950 950);
DISPLAY 0.617021 (4950 950);
PAINT SKYBLUE (4950 950);
FORCEPROP 1 LAST MATERIAL CHIP
R 1
J 0
(4950 975);
DISPLAY 0.617021 (4950 975);
PAINT SKYBLUE (4950 975);
FORCEPROP 1 LAST TOLERANCE 1.0%
R 1
J 0
(4900 975);
DISPLAY 0.617021 (4900 975);
PAINT SKYBLUE (4900 975);
FORCEPROP 1 LAST PART_NUMBER G21796-208
R 1
J 0
(4700 925);
DISPLAY 0.617021 (4700 925);
PAINT BLUE (4700 925);
FORCEPROP 1 LAST LOCATION R6L7
R 1
J 0
(4750 925);
DISPLAY 0.617021 (4750 925);
PAINT AQUA (4750 925);
FORCEPROP 1 LAST PACK_TYPE 0402
R 1
J 0
(4950 1125);
DISPLAY 0.617021 (4950 1125);
PAINT SKYBLUE (4950 1125);
FORCEPROP 1 LAST PATH I52
R 1
J 0
(4650 925);
DISPLAY 0.978723 (4650 925);
PAINT WHITE (4650 925);
DISPLAY INVISIBLE (4650 925);
FORCEPROP 2 LAST CDS_LOCATION R6L7
R 1
J 0
(4750 925);
DISPLAY 0.617021 (4750 925);
PAINT AQUA (4750 925);
DISPLAY INVISIBLE (4750 925);
FORCEPROP 1 LASTPIN (4800 875) $PN 1
R 1
J 0
(4788 887);
DISPLAY 0.787234 (4788 887);
PAINT ORANGE (4788 887);
DISPLAY INVISIBLE (4788 887);
FORCEPROP 2 LAST CDS_LIB mstr_discrete
J 0
(4800 975);
PAINT ORANGE (4800 975);
DISPLAY INVISIBLE (4800 975);
FORCEPROP 2 LAST CDS_SEC 1
J 0
(4825 1100);
PAINT MONO (4825 1100);
DISPLAY INVISIBLE (4825 1100);
FORCEPROP 2 LAST $SEC 1
J 0
(4825 1100);
PAINT MONO (4825 1100);
DISPLAY INVISIBLE (4825 1100);
FORCEPROP 1 LASTPIN (4800 1075) $PN 2
R 1
J 0
(4788 1037);
DISPLAY 0.787234 (4788 1037);
PAINT ORANGE (4788 1037);
DISPLAY INVISIBLE (4788 1037);
FORCEADD SHUNT..1
(4975 50);
FORCEPROP 1 LAST PART_NUMBER N_A
J 0
(4900 -40);
DISPLAY 0.617021 (4900 -40);
PAINT BLUE (4900 -40);
FORCEPROP 1 LASTPIN (4825 50) $PN 1
J 2
(4875 60);
DISPLAY 0.617021 (4875 60);
PAINT ORANGE (4875 60);
FORCEPROP 1 LAST LOCATION SH8L1
J 0
(4900 100);
DISPLAY 0.617021 (4900 100);
PAINT AQUA (4900 100);
FORCEPROP 1 LASTPIN (5125 50) $PN 2
J 0
(5085 60);
DISPLAY 0.617021 (5085 60);
PAINT ORANGE (5085 60);
FORCEPROP 1 LAST PIN_SHORT A:B
J 0
(4900 -200);
DISPLAY 1.021277 (4900 -200);
PAINT ORANGE (4900 -200);
DISPLAY INVISIBLE (4900 -200);
FORCEPROP 1 LAST PACK_TYPE SH0201
J 0
(4915 -135);
DISPLAY 0.978723 (4915 -135);
PAINT SKYBLUE (4915 -135);
DISPLAY INVISIBLE (4915 -135);
FORCEPROP 1 LAST MATERIAL EMPTY
J 0
(4900 -85);
DISPLAY 0.978723 (4900 -85);
PAINT RED (4900 -85);
DISPLAY INVISIBLE (4900 -85);
FORCEPROP 2 LAST CDS_LIB mstr_misc
J 0
(4975 50);
PAINT ORANGE (4975 50);
DISPLAY INVISIBLE (4975 50);
FORCEPROP 1 LAST PATH I53
J 0
(4925 150);
DISPLAY 0.978723 (4925 150);
PAINT ORANGE (4925 150);
DISPLAY INVISIBLE (4925 150);
FORCEPROP 0 LAST SEC 1
J 0
(4900 150);
DISPLAY 0.680851 (4900 150);
PAINT MONO (4900 150);
DISPLAY INVISIBLE (4900 150);
FORCEPROP 2 LAST SEC_TYPE SH0201
J 0
(4925 200);
DISPLAY 1.021277 (4925 200);
PAINT ORANGE (4925 200);
DISPLAY INVISIBLE (4925 200);
FORCEADD PVTT_KLM..1
(3025 3700);
FORCEPROP 3 LASTPIN (3025 3650) SIG_NAME PVTT_KLM\g
J 0
(3035 3660);
DISPLAY 0.659574 (3035 3660);
PAINT MONO (3035 3660);
DISPLAY INVISIBLE (3035 3660);
FORCEPROP 1 LAST BODY_TYPE PLUMBING
J 0
(2980 3657);
DISPLAY 0.340426 (2980 3657);
PAINT GREEN (2980 3657);
DISPLAY INVISIBLE (2980 3657);
FORCEPROP 1 LAST VOLTAGE 0.6V
J 0
(2980 3657);
DISPLAY 0.340426 (2980 3657);
PAINT SKYBLUE (2980 3657);
DISPLAY INVISIBLE (2980 3657);
FORCEPROP 2 LAST CDS_LIB mstr_symbols
J 0
(3025 3700);
PAINT ORANGE (3025 3700);
DISPLAY INVISIBLE (3025 3700);
FORCEPROP 1 LAST HDL_POWER PVTT_KLM
J 1
(3025 3750);
DISPLAY 0.872340 (3025 3750);
PAINT GREEN (3025 3750);
DISPLAY INVISIBLE (3025 3750);
FORCEPROP 2 LAST ROOM VTT_KLM_PWR_VR
J 0
(3275 3800);
PAINT ORANGE (3275 3800);
DISPLAY INVISIBLE (3275 3800);
FORCEPROP 1 LAST PATH I6
J 0
(3075 3725);
DISPLAY 0.872340 (3075 3725);
PAINT AQUA (3075 3725);
DISPLAY INVISIBLE (3075 3725);
FORCEPROP 2 LAST BOM_COST MEM_KLM_VTT_DEF
J 0
(3100 3800);
PAINT MONO (3100 3800);
DISPLAY INVISIBLE (3100 3800);
FORCEADD OFFPAGE..2
(4975 1850);
FORCEPROP 2 LAST $XR0 229 
J 0
(5164 1850);
DISPLAY 0.638298 (5164 1850);
PAINT MONO (5164 1850);
FORCEPROP 2 LAST $XR1 190 
J 0
(5284 1850);
DISPLAY 0.638298 (5284 1850);
PAINT MONO (5284 1850);
FORCEPROP 1 LAST COMMENT_BODY TRUE
J 0
(4930 1755);
DISPLAY 0.872340 (4930 1755);
PAINT GREEN (4930 1755);
DISPLAY INVISIBLE (4930 1755);
FORCEPROP 2 LAST CDS_LIB mstr_standard
J 0
(4975 1850);
DISPLAY 0.744681 (4975 1850);
PAINT MONO (4975 1850);
DISPLAY INVISIBLE (4975 1850);
FORCEPROP 2 LAST PATH I8
J 0
(5178 1883);
DISPLAY 1.021277 (5178 1883);
PAINT ORANGE (5178 1883);
DISPLAY INVISIBLE (5178 1883);
FORCEPROP 1 LAST OFFPAGE TRUE
J 0
(5300 1725);
DISPLAY 0.872340 (5300 1725);
PAINT GREEN (5300 1725);
DISPLAY INVISIBLE (5300 1725);
FORCEADD PVTT_KLM..1
(5550 1600);
FORCEPROP 3 LASTPIN (5550 1550) SIG_NAME PVTT_KLM\g
J 0
(5560 1560);
DISPLAY 0.659574 (5560 1560);
PAINT MONO (5560 1560);
DISPLAY INVISIBLE (5560 1560);
FORCEPROP 1 LAST VOLTAGE 0.6V
J 0
(5505 1557);
DISPLAY 0.340426 (5505 1557);
PAINT SKYBLUE (5505 1557);
DISPLAY INVISIBLE (5505 1557);
FORCEPROP 1 LAST HDL_POWER PVTT_KLM
J 1
(5550 1650);
DISPLAY 0.872340 (5550 1650);
PAINT GREEN (5550 1650);
DISPLAY INVISIBLE (5550 1650);
FORCEPROP 1 LAST PATH I9
J 0
(5600 1625);
DISPLAY 0.872340 (5600 1625);
PAINT AQUA (5600 1625);
DISPLAY INVISIBLE (5600 1625);
FORCEPROP 1 LAST BODY_TYPE PLUMBING
J 0
(5505 1557);
DISPLAY 0.340426 (5505 1557);
PAINT GREEN (5505 1557);
DISPLAY INVISIBLE (5505 1557);
FORCEPROP 2 LAST CDS_LIB mstr_symbols
J 0
(5550 1600);
PAINT ORANGE (5550 1600);
DISPLAY INVISIBLE (5550 1600);
FORCEADD CAD_NOTE..1
(2275 1600);
FORCEPROP 0 LAST L1 PLACE CLOSE TO CONTROLLER
J 0
(2093 1508);
DISPLAY 0.617021 (2093 1508);
PAINT WHITE (2093 1508);
FORCEPROP 2 LAST CDS_LIB mstr_symbols
J 0
(2275 1600);
PAINT ORANGE (2275 1600);
DISPLAY INVISIBLE (2275 1600);
FORCEPROP 1 LAST COMMENT_BODY TRUE
J 0
(2300 1700);
DISPLAY 0.978723 (2300 1700);
PAINT ORANGE (2300 1700);
DISPLAY INVISIBLE (2300 1700);
FORCEADD PRELIM..6
(1585 1065);
PAINT GRAY (1585 1065);
FORCEPROP 2 LAST CDS_LIB mstr_misc
J 0
(1585 1065);
PAINT ORANGE (1585 1065);
DISPLAY INVISIBLE (1585 1065);
FORCEPROP 1 LAST COMMENT_BODY TRUE
J 0
(1585 1065);
PAINT ORANGE (1585 1065);
DISPLAY INVISIBLE (1585 1065);
FORCEADD CAD_NOTE..1
(125 2775);
FORCEPROP 0 LAST L1 PLACE CLOSE TO CONTROLLER
J 0
(38 2683);
DISPLAY 0.617021 (38 2683);
PAINT WHITE (38 2683);
FORCEPROP 2 LAST CDS_LIB mstr_symbols
J 0
(125 2775);
PAINT ORANGE (125 2775);
DISPLAY INVISIBLE (125 2775);
FORCEPROP 1 LAST COMMENT_BODY TRUE
J 0
(150 2875);
DISPLAY 0.978723 (150 2875);
PAINT ORANGE (150 2875);
DISPLAY INVISIBLE (150 2875);
FORCEADD CAD_NOTE..1
(4350 3700);
FORCEPROP 1 LAST COMMENT_BODY TRUE
J 0
(4375 3800);
DISPLAY 0.978723 (4375 3800);
PAINT ORANGE (4375 3800);
DISPLAY INVISIBLE (4375 3800);
FORCEPROP 2 LAST CDS_LIB mstr_symbols
J 0
(4350 3700);
PAINT ORANGE (4350 3700);
DISPLAY INVISIBLE (4350 3700);
FORCEADD DNS..2
(-295 670);
PAINT RED (-295 670);
FORCEPROP 1 LAST COMMENT_BODY TRUE
R 1
J 0
(-220 445);
DISPLAY 0.872340 (-220 445);
PAINT GREEN (-220 445);
DISPLAY INVISIBLE (-220 445);
FORCEPROP 2 LAST CDS_LIB mstr_misc
J 0
(-295 670);
PAINT ORANGE (-295 670);
DISPLAY INVISIBLE (-295 670);
FORCEADD CAD_NOTE..1
(4750 -225);
FORCEPROP 0 LAST L2 OF PVTT PLANE
J 0
(4632 -372);
DISPLAY 0.617021 (4632 -372);
PAINT WHITE (4632 -372);
FORCEPROP 0 LAST L1 PLACE NEAR CENTER
J 0
(4632 -320);
DISPLAY 0.617021 (4632 -320);
PAINT WHITE (4632 -320);
FORCEPROP 2 LAST CDS_LIB mstr_symbols
J 0
(4750 -225);
PAINT ORANGE (4750 -225);
DISPLAY INVISIBLE (4750 -225);
FORCEPROP 1 LAST COMMENT_BODY TRUE
J 0
(4775 -125);
DISPLAY 0.978723 (4775 -125);
PAINT ORANGE (4775 -125);
DISPLAY INVISIBLE (4775 -125);
FORCEADD CAD_NOTE..1
(4800 250);
FORCEPROP 0 LAST L1 SPOF
J 0
(4661 101);
DISPLAY 0.617021 (4661 101);
PAINT WHITE (4661 101);
FORCEPROP 2 LAST CDS_LIB mstr_symbols
J 0
(4800 250);
PAINT ORANGE (4800 250);
DISPLAY INVISIBLE (4800 250);
FORCEPROP 1 LAST COMMENT_BODY TRUE
J 0
(4825 350);
DISPLAY 0.978723 (4825 350);
PAINT ORANGE (4825 350);
DISPLAY INVISIBLE (4825 350);
FORCEADD DNS..2
(-345 -380);
PAINT RED (-345 -380);
FORCEPROP 1 LAST COMMENT_BODY TRUE
R 1
J 0
(-270 -605);
DISPLAY 0.872340 (-270 -605);
PAINT GREEN (-270 -605);
DISPLAY INVISIBLE (-270 -605);
FORCEPROP 2 LAST CDS_LIB mstr_misc
J 0
(-345 -380);
PAINT ORANGE (-345 -380);
DISPLAY INVISIBLE (-345 -380);
FORCEADD DNS..3
(4980 45);
PAINT RED (4980 45);
FORCEPROP 1 LAST COMMENT_BODY TRUE
R 1
J 0
(5055 -180);
DISPLAY 0.872340 (5055 -180);
PAINT GREEN (5055 -180);
DISPLAY INVISIBLE (5055 -180);
FORCEPROP 2 LAST CDS_LIB mstr_misc
J 0
(4980 45);
PAINT ORANGE (4980 45);
DISPLAY INVISIBLE (4980 45);
FORCEADD INTEL_CORP_BPAGE..1
(5975 -1075);
FORCEPROP 1 LAST CDS_CON_LAST_MODIFIED Tue Dec 01 11:52:28 2015
J 0
(4550 -750);
PAINT GREEN (4550 -750);
DISPLAY INVISIBLE (4550 -750);
FORCEPROP 1 LAST CUSTOM_TXT_CDS <CURRENT_DESIGN_SHEET> OF <TOTAL_DESIGN_SHEETS>
J 0
(5475 -1050);
PAINT GREEN (5475 -1050);
FORCEPROP 1 LAST CUSTOM_TXT_CDS <CON_LAST_MODIFIED>
J 0
(4050 -725);
PAINT GREEN (4050 -725);
FORCEPROP 2 LAST CUSTOM_TXT_CDS <XR_PAGE_TITLE>
J 0
(-1915 4175);
DISPLAY 0.638298 (-1915 4175);
PAINT PINK (-1915 4175);
DISPLAY INVISIBLE (-1915 4175);
FORCEPROP 1 LAST SCH_TITLE DDR VTT VR CHANNEL KLM
J 0
(-1975 -1025);
DISPLAY 1.212766 (-1975 -1025);
PAINT GREEN (-1975 -1025);
FORCEPROP 1 LAST SCH_ADDRESS1 2200 MISSION COLLEGE BLVD.
J 0
(2000 -950);
DISPLAY 0.617021 (2000 -950);
PAINT GREEN (2000 -950);
FORCEPROP 1 LAST SCH_ADDRESS2 P.O. BOX 58119
J 0
(2000 -1000);
DISPLAY 0.617021 (2000 -1000);
PAINT GREEN (2000 -1000);
FORCEPROP 1 LAST SCH_ADDRESS3 SANTA CLARA, CA 95052-8119
J 0
(2000 -1050);
DISPLAY 0.617021 (2000 -1050);
PAINT GREEN (2000 -1050);
FORCEPROP 1 LAST SCH_REV 2.420
J 0
(5725 -925);
DISPLAY 0.978723 (5725 -925);
PAINT YELLOW (5725 -925);
FORCEPROP 1 LAST SCH_DEPT BESD
J 1
(1525 -975);
DISPLAY 1.212766 (1525 -975);
PAINT YELLOW (1525 -975);
FORCEPROP 1 LAST SCH_NUMBER H4694802
J 0
(4675 -925);
DISPLAY 1.212766 (4675 -925);
PAINT YELLOW (4675 -925);
FORCEPROP 2 LAST PAGE_BORDER TRUE
J 0
(-1915 4175);
DISPLAY 0.659574 (-1915 4175);
PAINT PINK (-1915 4175);
DISPLAY INVISIBLE (-1915 4175);
FORCEPROP 2 LAST CDS_LIB mstr_symbols
J 0
(5975 -1075);
PAINT ORANGE (5975 -1075);
DISPLAY INVISIBLE (5975 -1075);
FORCEPROP 1 LAST COMMENT_BODY TRUE
J 0
(5987 -1063);
DISPLAY 0.446809 (5987 -1063);
PAINT GREEN (5987 -1063);
DISPLAY INVISIBLE (5987 -1063);
FORCEPROP 2 LAST CDS_XR_PAGE_TITLE CR-230 : @BASEBOARD_FAB2_LIB.BASEBOARD_FAB2(SCH_1):PAGE230
J 0
(-1915 4175);
DISPLAY 0.638298 (-1915 4175);
PAINT PINK (-1915 4175);
DISPLAY INVISIBLE (-1915 4175);
WIRE 16 -1 (3025 3325)(3025 3175);
WIRE 16 -1 (3025 3175)(3375 3175);
WIRE 16 -1 (3375 3325)(3375 3175);
WIRE 16 -1 (3375 3175)(3750 3175);
WIRE 16 -1 (3750 3175)(3775 3175);
WIRE 16 -1 (3750 3100)(3750 3175);
WIRE 16 -1 (3775 3325)(3775 3175);
WIRE 16 -1 (3875 1450)(3875 1550);
WIRE 16 -1 (4800 875)(4800 800);
WIRE 16 -1 (4800 800)(4000 800);
WIRE 16 -1 (4000 950)(4000 800);
WIRE 16 -1 (4000 800)(4000 725);
WIRE 16 -1 (2350 650)(2350 775);
WIRE 16 -1 (1875 925)(2025 925);
WIRE 16 -1 (2025 925)(2025 875);
WIRE 16 -1 (1875 875)(2025 875);
WIRE 16 -1 (2025 875)(2025 775);
WIRE 16 -1 (1875 775)(2025 775);
WIRE 16 -1 (2025 775)(2025 650);
WIRE 16 -1 (475 2175)(475 2300);
WIRE 16 -1 (50 2275)(50 2175);
WIRE 16 -1 (475 1425)(475 1325);
WIRE 16 -1 (1275 1325)(1100 1325);
WIRE 16 -1 (1100 1325)(1100 2550);
WIRE 16 -1 (475 2550)(1100 2550);
WIRE 16 -1 (475 2500)(475 2550);
WIRE 16 -1 (50 2550)(475 2550);
WIRE 16 -1 (50 2475)(50 2550);
WIRE 16 -1 (50 2550)(-1000 2550);
WIRE 16 -1 (-1000 2550)(-1000 1575);
WIRE 16 -1 (-1000 2550)(-1425 2550);
WIRE 16 -1 (-1425 2750)(-1425 2550);
WIRE 16 -1 (-775 1575)(-1000 1575);
WIRE 16 -1 (-350 -550)(-350 -475);
WIRE 16 -1 (50 1775)(-300 1775);
WIRE 16 -1 (-300 1775)(-375 1775);
WIRE 16 -1 (-300 775)(-300 1775);
WIRE 16 -1 (-375 2025)(-375 1775);
WIRE 16 -1 (3500 2125)(3500 2275);
WIRE 16 -1 (375 825)(375 875);
WIRE 16 -1 (3775 3525)(3775 3600);
WIRE 16 -1 (3775 3600)(3375 3600);
WIRE 16 -1 (3375 3525)(3375 3600);
WIRE 16 -1 (3025 3600)(3375 3600);
WIRE 16 -1 (3025 3600)(3025 3650);
WIRE 16 -1 (3025 3600)(3025 3525);
WIRE 16 -1 (4000 1150)(4000 1325);
WIRE 16 -1 (4800 1325)(4000 1325);
WIRE 16 -1 (1875 1325)(4000 1325);
WIRE 16 -1 (4800 1075)(4800 1325);
WIRE 16 -1 (5550 1325)(4800 1325);
WIRE 16 -1 (5550 50)(5550 1325);
WIRE 16 -1 (5550 1550)(5550 1325);
WIRE 16 -1 (5125 50)(5550 50);
WIRE 16 2175 (5800 2875)(5800 3850);
WIRE 16 2175 (5800 2875)(2800 2875);
WIRE 16 2175 (5800 3850)(2800 3850);
WIRE 16 2175 (2800 2875)(2800 3850);
WIRE 16 2175 (5225 -425)(5225 150);
WIRE 16 2175 (4575 -425)(5225 -425);
WIRE 16 2175 (4575 150)(5225 150);
WIRE 16 2175 (4575 -425)(4575 150);
WIRE 16 -1 (4925 1850)(4250 1850);
FORCEPROP 2 LAST SIG_NAME PWRGD_PVTT_CPU1
J 0
(4347 1860);
DISPLAY 0.617021 (4347 1860);
PAINT ORANGE (4347 1860);
WIRE 16 -1 (4825 50)(925 50);
FORCEPROP 2 LAST SIG_NAME VR_PVTT_KLM_SNS
J 0
(965 55);
DISPLAY 0.617021 (965 55);
PAINT ORANGE (965 55);
FORCEPROP 2 LASTPROP $XRERR UNIQUE?
J 0
(725 55);
DISPLAY 0.638298 (725 55);
PAINT MONO (725 55);
DISPLAY INVISIBLE (725 55);
WIRE 16 -1 (925 975)(925 50);
WIRE 16 -1 (1275 975)(925 975);
WIRE 16 273 (2275 3625)(2275 3125);
WIRE 16 273 (2275 3725)(2275 3625);
WIRE 16 273 (1125 3625)(2275 3625);
WIRE 16 273 (2275 3125)(1125 3125);
WIRE 16 273 (1125 3125)(1125 3625);
WIRE 16 273 (1125 3625)(1125 3725);
WIRE 16 273 (1125 3725)(2275 3725);
WIRE 16 -1 (3875 1750)(3875 1850);
WIRE 16 -1 (4050 1850)(3875 1850);
WIRE 16 -1 (3875 1850)(3500 1850);
FORCEPROP 2 LAST SIG_NAME PWRGD_PVTT_KLM_CPU1_R
J 0
(3522 1860);
DISPLAY 0.617021 (3522 1860);
PAINT ORANGE (3522 1860);
FORCEPROP 2 LASTPROP $XRERR UNIQUE?
J 0
(3282 1860);
DISPLAY 0.638298 (3282 1860);
PAINT MONO (3282 1860);
DISPLAY INVISIBLE (3282 1860);
WIRE 16 -1 (3500 1925)(3500 1850);
WIRE 16 -1 (3475 1850)(3500 1850);
WIRE 16 -1 (3475 1025)(3475 1850);
WIRE 16 -1 (1875 1025)(3475 1025);
WIRE 16 2175 (2075 1675)(2875 1675);
WIRE 16 2175 (2075 550)(2075 1675);
WIRE 16 2175 (2875 1675)(2875 550);
WIRE 16 2175 (2875 550)(2075 550);
WIRE 16 -1 (2350 975)(2350 1225);
WIRE 16 -1 (1875 1225)(2350 1225);
FORCEPROP 2 LAST SIG_NAME VR_PVTT_KLM_VREF
J 0
(1931 1235);
DISPLAY 0.617021 (1931 1235);
PAINT ORANGE (1931 1235);
FORCEPROP 2 LASTPROP $XRERR UNIQUE?
J 0
(1691 1235);
DISPLAY 0.638298 (1691 1235);
PAINT MONO (1691 1235);
DISPLAY INVISIBLE (1691 1235);
WIRE 16 2175 (-50 2875)(900 2875);
WIRE 16 2175 (-50 1250)(-50 2875);
WIRE 16 2175 (900 1250)(900 2875);
WIRE 16 2175 (-50 1250)(900 1250);
WIRE 16 -1 (1275 825)(1025 825);
WIRE 16 -1 (1025 825)(1025 1775);
WIRE 16 -1 (1025 1775)(475 1775);
WIRE 16 -1 (475 1625)(475 1775);
WIRE 16 -1 (250 1775)(475 1775);
FORCEPROP 2 LAST SIG_NAME VR_PVTT_KLM_BIAS
J 0
(320 1795);
DISPLAY 0.617021 (320 1795);
PAINT ORANGE (320 1795);
FORCEPROP 2 LASTPROP $XRERR UNIQUE?
J 0
(80 1795);
DISPLAY 0.638298 (80 1795);
PAINT MONO (80 1795);
DISPLAY INVISIBLE (80 1795);
WIRE 16 -1 (375 1075)(375 1175);
FORCEPROP 2 LAST SIG_NAME VSENSE_PVDDQ_KLM_VTT
J 0
(-207 1185);
DISPLAY 0.617021 (-207 1185);
PAINT ORANGE (-207 1185);
FORCEPROP 2 LASTPROP $XRERR UNIQUE?
J 0
(-447 1185);
DISPLAY 0.638298 (-447 1185);
PAINT MONO (-447 1185);
DISPLAY INVISIBLE (-447 1185);
WIRE 16 -1 (375 1175)(1275 1175);
WIRE 16 -1 (-500 1175)(375 1175);
WIRE 16 -1 (-500 1175)(-500 1575);
WIRE 16 -1 (-500 1575)(-575 1575);
WIRE 16 -1 (1275 1075)(650 1075);
FORCEPROP 2 LAST SIG_NAME FM_PVTT_KLM_EN_R
J 0
(49 165);
DISPLAY 0.617021 (49 165);
PAINT ORANGE (49 165);
FORCEPROP 2 LASTPROP $XRERR UNIQUE?
J 0
(-191 165);
DISPLAY 0.638298 (-191 165);
PAINT MONO (-191 165);
DISPLAY INVISIBLE (-191 165);
WIRE 16 -1 (650 1075)(650 150);
WIRE 16 -1 (650 150)(-300 150);
WIRE 16 -1 (-300 150)(-300 575);
WIRE 16 -1 (-300 150)(-350 150);
WIRE 16 -1 (-400 150)(-350 150);
WIRE 16 -1 (-350 -275)(-350 150);
WIRE 16 -1 (-600 150)(-1350 150);
FORCEPROP 2 LAST SIG_NAME PWRGD_PVDDQ_KLM
J 0
(-1300 165);
DISPLAY 0.617021 (-1300 165);
PAINT ORANGE (-1300 165);
DOT 1 (-350 150);
DOT 1 (-300 150);
DOT 1 (-300 1775);
DOT 1 (-1000 2550);
DOT 1 (375 1175);
DOT 1 (475 1775);
DOT 1 (2025 775);
DOT 1 (2025 875);
DOT 1 (50 2550);
DOT 1 (475 2550);
DOT 1 (1125 3625);
DOT 1 (4000 800);
DOT 1 (3500 1850);
DOT 1 (4000 1325);
DOT 1 (3875 1850);
DOT 1 (2275 3625);
DOT 1 (3025 3600);
DOT 1 (3375 3175);
DOT 1 (3375 3600);
DOT 1 (3750 3175);
DOT 1 (4800 1325);
DOT 1 (5550 1325);
FORCENOTE
ROOM = VTT_KLM_PWR_VR
(-1990 -826) 0;
DISPLAY LEFT (-1990 -826);
DISPLAY 1.255319 (-1990 -826);
PAINT PURPLE (-1990 -826);
FORCENOTE
BOM_COST = MEM_VRD_VTT_KLM
(-1990 -901) 0;
DISPLAY LEFT (-1990 -901);
DISPLAY 1.255319 (-1990 -901);
PAINT PURPLE (-1990 -901);
FORCENOTE
CRTICAL: PLACE 0 OHM NEAR  VDDQ SENSE RESISTOR.
(-1810 1392) 0;
DISPLAY LEFT (-1810 1392);
DISPLAY 1.021277 (-1810 1392);
PAINT PURPLE (-1810 1392);
FORCENOTE
DC TOL= +/-1.5%
(1171 3456) 0;
DISPLAY LEFT (1171 3456);
DISPLAY 0.808511 (1171 3456);
PAINT PURPLE (1171 3456);
FORCENOTE
RIPPLE GUIDELINE= +/-1%
(1171 3506) 0;
DISPLAY LEFT (1171 3506);
DISPLAY 0.808511 (1171 3506);
PAINT PURPLE (1171 3506);
FORCENOTE
VOUT=0.5 VDDQ
(1171 3556) 0;
DISPLAY LEFT (1171 3556);
DISPLAY 0.808511 (1171 3556);
PAINT PURPLE (1171 3556);
FORCENOTE
AC & RIPPLE=+3.5/-7.3%
(1171 3406) 0;
DISPLAY LEFT (1171 3406);
DISPLAY 0.808511 (1171 3406);
PAINT PURPLE (1171 3406);
FORCENOTE
IOUT TDC=+/-1.7A
(1171 3306) 0;
DISPLAY LEFT (1171 3306);
DISPLAY 0.808511 (1171 3306);
PAINT PURPLE (1171 3306);
FORCENOTE
IOUT PEAK=+/-1.7A
(1171 3356) 0;
DISPLAY LEFT (1171 3356);
DISPLAY 0.808511 (1171 3356);
PAINT PURPLE (1171 3356);
FORCENOTE
IOUT DI/DT=6A/US
(1171 3206) 0;
DISPLAY LEFT (1171 3206);
DISPLAY 0.808511 (1171 3206);
PAINT PURPLE (1171 3206);
FORCENOTE
PVTT DDR SPECIFICATION:
(1171 3656) 0;
DISPLAY LEFT (1171 3656);
PAINT PURPLE (1171 3656);
FORCENOTE
IOUT STEP=-1.546/+1.523A
(1171 3256) 0;
DISPLAY LEFT (1171 3256);
DISPLAY 0.808511 (1171 3256);
PAINT PURPLE (1171 3256);
FORCENOTE
PLACED BETWEEN DIMMS
(4209 3572) 0;
DISPLAY LEFT (4209 3572);
DISPLAY 1.021277 (4209 3572);
PAINT PURPLE (4209 3572);
QUIT
